FILE_TYPE = MACRO_DRAWING;
SET COLOR_WIRE YELLOW;
SET COLOR_PROP ORANGE;
SET COLOR_DOT WHITE;
SET COLOR_ARC YELLOW;
SET COLOR_BODY GREEN;
SET COLOR_NOTE PURPLE;
SET PROP_DISPLAY VALUE;
SET PAGE_NUMBER P99;
FORCEADD OFFPAGE..5
(-8500 2000);
FORCEPROP 2 LAST $XR0 39 
J 0
(-8754 2000);
DISPLAY 0.638298 (-8754 2000);
PAINT MONO (-8754 2000);
FORCEPROP 2 LAST CDS_LIB mstr_standard
J 0
(-8500 2000);
DISPLAY 0.808511 (-8500 2000);
DISPLAY INVISIBLE (-8500 2000);
FORCEPROP 1 LAST OFFPAGE TRUE
J 0
(-8175 1875);
DISPLAY 0.872340 (-8175 1875);
PAINT GREEN (-8175 1875);
DISPLAY INVISIBLE (-8175 1875);
FORCEPROP 1 LAST COMMENT_BODY TRUE
J 0
(-8400 1925);
DISPLAY 0.872340 (-8400 1925);
PAINT GREEN (-8400 1925);
DISPLAY INVISIBLE (-8400 1925);
FORCEPROP 2 LAST PATH I1
J 0
(-8750 2050);
DISPLAY 1.021277 (-8750 2050);
DISPLAY INVISIBLE (-8750 2050);
FORCEADD OFFPAGE..6
(-8500 3600);
FORCEPROP 2 LAST $XR0 39 
J 0
(-8779 3600);
DISPLAY 0.638298 (-8779 3600);
PAINT MONO (-8779 3600);
FORCEPROP 2 LAST CDS_LIB mstr_standard
J 0
(-8500 3600);
DISPLAY 0.723404 (-8500 3600);
PAINT MONO (-8500 3600);
DISPLAY INVISIBLE (-8500 3600);
FORCEPROP 1 LAST OFFPAGE TRUE
J 0
(-8175 3475);
DISPLAY 0.872340 (-8175 3475);
PAINT GREEN (-8175 3475);
DISPLAY INVISIBLE (-8175 3475);
FORCEPROP 1 LAST COMMENT_BODY TRUE
J 0
(-8400 3525);
DISPLAY 0.872340 (-8400 3525);
PAINT GREEN (-8400 3525);
DISPLAY INVISIBLE (-8400 3525);
FORCEPROP 2 LAST PATH I10
J 0
(-8775 3650);
DISPLAY 1.021277 (-8775 3650);
DISPLAY INVISIBLE (-8775 3650);
FORCEADD TAP..1
(-6200 4000);
FORCEPROP 3 LASTPIN (-6250 4000) SIG_NAME M_C_CPU1_SA_DQ<3>
J 0
(-6240 4010);
DISPLAY 0.659574 (-6240 4010);
PAINT MONO (-6240 4010);
DISPLAY INVISIBLE (-6240 4010);
FORCEPROP 1 LASTPIN (-6250 4000) BN 3
J 0
(-6262 4008);
DISPLAY 0.489362 (-6262 4008);
PAINT GREEN (-6262 4008);
FORCEPROP 2 LAST CDS_LIB mstr_standard
J 0
(-6200 4000);
DISPLAY 0.723404 (-6200 4000);
PAINT MONO (-6200 4000);
DISPLAY INVISIBLE (-6200 4000);
FORCEPROP 1 LAST BODY_TYPE PLUMBING
J 0
(-6200 4050);
DISPLAY 0.872340 (-6200 4050);
PAINT GREEN (-6200 4050);
DISPLAY INVISIBLE (-6200 4050);
FORCEPROP 1 LAST HDL_TAP TRUE
J 0
(-5875 3875);
DISPLAY 0.872340 (-5875 3875);
DISPLAY INVISIBLE (-5875 3875);
FORCEPROP 1 LAST PATH I100
J 0
(-6202 4000);
DISPLAY 0.872340 (-6202 4000);
PAINT GREEN (-6202 4000);
DISPLAY INVISIBLE (-6202 4000);
FORCEADD TAP..1
(-6200 4050);
FORCEPROP 3 LASTPIN (-6250 4050) SIG_NAME M_C_CPU1_SA_DQ<4>
J 0
(-6240 4060);
DISPLAY 0.659574 (-6240 4060);
PAINT MONO (-6240 4060);
DISPLAY INVISIBLE (-6240 4060);
FORCEPROP 1 LASTPIN (-6250 4050) BN 4
J 0
(-6262 4058);
DISPLAY 0.489362 (-6262 4058);
PAINT GREEN (-6262 4058);
FORCEPROP 2 LAST CDS_LIB mstr_standard
J 0
(-6200 4050);
DISPLAY 0.723404 (-6200 4050);
PAINT MONO (-6200 4050);
DISPLAY INVISIBLE (-6200 4050);
FORCEPROP 1 LAST BODY_TYPE PLUMBING
J 0
(-6200 4100);
DISPLAY 0.872340 (-6200 4100);
PAINT GREEN (-6200 4100);
DISPLAY INVISIBLE (-6200 4100);
FORCEPROP 1 LAST HDL_TAP TRUE
J 0
(-5875 3925);
DISPLAY 0.872340 (-5875 3925);
DISPLAY INVISIBLE (-5875 3925);
FORCEPROP 1 LAST PATH I101
J 0
(-6202 4050);
DISPLAY 0.872340 (-6202 4050);
PAINT GREEN (-6202 4050);
DISPLAY INVISIBLE (-6202 4050);
FORCEADD TAP..1
(-6200 4100);
FORCEPROP 3 LASTPIN (-6250 4100) SIG_NAME M_C_CPU1_SA_DQ<5>
J 0
(-6240 4110);
DISPLAY 0.659574 (-6240 4110);
PAINT MONO (-6240 4110);
DISPLAY INVISIBLE (-6240 4110);
FORCEPROP 1 LASTPIN (-6250 4100) BN 5
J 0
(-6262 4108);
DISPLAY 0.489362 (-6262 4108);
PAINT GREEN (-6262 4108);
FORCEPROP 2 LAST CDS_LIB mstr_standard
J 0
(-6200 4100);
DISPLAY 0.723404 (-6200 4100);
PAINT MONO (-6200 4100);
DISPLAY INVISIBLE (-6200 4100);
FORCEPROP 1 LAST BODY_TYPE PLUMBING
J 0
(-6200 4150);
DISPLAY 0.872340 (-6200 4150);
PAINT GREEN (-6200 4150);
DISPLAY INVISIBLE (-6200 4150);
FORCEPROP 1 LAST HDL_TAP TRUE
J 0
(-5875 3975);
DISPLAY 0.872340 (-5875 3975);
DISPLAY INVISIBLE (-5875 3975);
FORCEPROP 1 LAST PATH I102
J 0
(-6202 4100);
DISPLAY 0.872340 (-6202 4100);
PAINT GREEN (-6202 4100);
DISPLAY INVISIBLE (-6202 4100);
FORCEADD TAP..1
(-6200 4150);
FORCEPROP 3 LASTPIN (-6250 4150) SIG_NAME M_C_CPU1_SA_DQ<6>
J 0
(-6240 4160);
DISPLAY 0.659574 (-6240 4160);
PAINT MONO (-6240 4160);
DISPLAY INVISIBLE (-6240 4160);
FORCEPROP 1 LASTPIN (-6250 4150) BN 6
J 0
(-6262 4158);
DISPLAY 0.489362 (-6262 4158);
PAINT GREEN (-6262 4158);
FORCEPROP 2 LAST CDS_LIB mstr_standard
J 0
(-6200 4150);
DISPLAY 0.723404 (-6200 4150);
PAINT MONO (-6200 4150);
DISPLAY INVISIBLE (-6200 4150);
FORCEPROP 1 LAST BODY_TYPE PLUMBING
J 0
(-6200 4200);
DISPLAY 0.872340 (-6200 4200);
PAINT GREEN (-6200 4200);
DISPLAY INVISIBLE (-6200 4200);
FORCEPROP 1 LAST HDL_TAP TRUE
J 0
(-5875 4025);
DISPLAY 0.872340 (-5875 4025);
DISPLAY INVISIBLE (-5875 4025);
FORCEPROP 1 LAST PATH I103
J 0
(-6202 4150);
DISPLAY 0.872340 (-6202 4150);
PAINT GREEN (-6202 4150);
DISPLAY INVISIBLE (-6202 4150);
FORCEADD TAP..1
(-6200 4200);
FORCEPROP 3 LASTPIN (-6250 4200) SIG_NAME M_C_CPU1_SA_DQ<7>
J 0
(-6240 4210);
DISPLAY 0.659574 (-6240 4210);
PAINT MONO (-6240 4210);
DISPLAY INVISIBLE (-6240 4210);
FORCEPROP 1 LASTPIN (-6250 4200) BN 7
J 0
(-6262 4208);
DISPLAY 0.489362 (-6262 4208);
PAINT GREEN (-6262 4208);
FORCEPROP 2 LAST CDS_LIB mstr_standard
J 0
(-6200 4200);
DISPLAY 0.723404 (-6200 4200);
PAINT MONO (-6200 4200);
DISPLAY INVISIBLE (-6200 4200);
FORCEPROP 1 LAST BODY_TYPE PLUMBING
J 0
(-6200 4250);
DISPLAY 0.872340 (-6200 4250);
PAINT GREEN (-6200 4250);
DISPLAY INVISIBLE (-6200 4250);
FORCEPROP 1 LAST HDL_TAP TRUE
J 0
(-5875 4075);
DISPLAY 0.872340 (-5875 4075);
DISPLAY INVISIBLE (-5875 4075);
FORCEPROP 1 LAST PATH I104
J 0
(-6202 4200);
DISPLAY 0.872340 (-6202 4200);
PAINT GREEN (-6202 4200);
DISPLAY INVISIBLE (-6202 4200);
FORCEADD TAP..1
(-6200 4300);
FORCEPROP 3 LASTPIN (-6250 4300) SIG_NAME M_C_CPU1_SA_DQ<9>
J 0
(-6240 4310);
DISPLAY 0.659574 (-6240 4310);
PAINT MONO (-6240 4310);
DISPLAY INVISIBLE (-6240 4310);
FORCEPROP 1 LASTPIN (-6250 4300) BN 9
J 0
(-6262 4308);
DISPLAY 0.489362 (-6262 4308);
PAINT GREEN (-6262 4308);
FORCEPROP 2 LAST CDS_LIB mstr_standard
J 0
(-6200 4300);
DISPLAY 0.723404 (-6200 4300);
PAINT MONO (-6200 4300);
DISPLAY INVISIBLE (-6200 4300);
FORCEPROP 1 LAST BODY_TYPE PLUMBING
J 0
(-6200 4350);
DISPLAY 0.872340 (-6200 4350);
PAINT GREEN (-6200 4350);
DISPLAY INVISIBLE (-6200 4350);
FORCEPROP 1 LAST HDL_TAP TRUE
J 0
(-5875 4175);
DISPLAY 0.872340 (-5875 4175);
DISPLAY INVISIBLE (-5875 4175);
FORCEPROP 1 LAST PATH I105
J 0
(-6202 4300);
DISPLAY 0.872340 (-6202 4300);
PAINT GREEN (-6202 4300);
DISPLAY INVISIBLE (-6202 4300);
FORCEADD TAP..1
(-6200 4350);
FORCEPROP 3 LASTPIN (-6250 4350) SIG_NAME M_C_CPU1_SA_DQ<10>
J 0
(-6240 4360);
DISPLAY 0.659574 (-6240 4360);
PAINT MONO (-6240 4360);
DISPLAY INVISIBLE (-6240 4360);
FORCEPROP 1 LASTPIN (-6250 4350) BN 10
J 0
(-6262 4358);
DISPLAY 0.489362 (-6262 4358);
PAINT GREEN (-6262 4358);
FORCEPROP 2 LAST CDS_LIB mstr_standard
J 0
(-6200 4350);
DISPLAY 0.723404 (-6200 4350);
PAINT MONO (-6200 4350);
DISPLAY INVISIBLE (-6200 4350);
FORCEPROP 1 LAST BODY_TYPE PLUMBING
J 0
(-6200 4400);
DISPLAY 0.872340 (-6200 4400);
PAINT GREEN (-6200 4400);
DISPLAY INVISIBLE (-6200 4400);
FORCEPROP 1 LAST HDL_TAP TRUE
J 0
(-5875 4225);
DISPLAY 0.872340 (-5875 4225);
DISPLAY INVISIBLE (-5875 4225);
FORCEPROP 1 LAST PATH I106
J 0
(-6202 4350);
DISPLAY 0.872340 (-6202 4350);
PAINT GREEN (-6202 4350);
DISPLAY INVISIBLE (-6202 4350);
FORCEADD TAP..1
(-6200 4250);
FORCEPROP 3 LASTPIN (-6250 4250) SIG_NAME M_C_CPU1_SA_DQ<8>
J 0
(-6240 4260);
DISPLAY 0.659574 (-6240 4260);
PAINT MONO (-6240 4260);
DISPLAY INVISIBLE (-6240 4260);
FORCEPROP 1 LASTPIN (-6250 4250) BN 8
J 0
(-6262 4258);
DISPLAY 0.489362 (-6262 4258);
PAINT GREEN (-6262 4258);
FORCEPROP 2 LAST CDS_LIB mstr_standard
J 0
(-6200 4250);
DISPLAY 0.723404 (-6200 4250);
PAINT MONO (-6200 4250);
DISPLAY INVISIBLE (-6200 4250);
FORCEPROP 1 LAST BODY_TYPE PLUMBING
J 0
(-6200 4300);
DISPLAY 0.872340 (-6200 4300);
PAINT GREEN (-6200 4300);
DISPLAY INVISIBLE (-6200 4300);
FORCEPROP 1 LAST HDL_TAP TRUE
J 0
(-5875 4125);
DISPLAY 0.872340 (-5875 4125);
DISPLAY INVISIBLE (-5875 4125);
FORCEPROP 1 LAST PATH I107
J 0
(-6202 4250);
DISPLAY 0.872340 (-6202 4250);
PAINT GREEN (-6202 4250);
DISPLAY INVISIBLE (-6202 4250);
FORCEADD TAP..1
(-6200 4400);
FORCEPROP 3 LASTPIN (-6250 4400) SIG_NAME M_C_CPU1_SA_DQ<11>
J 0
(-6240 4410);
DISPLAY 0.659574 (-6240 4410);
PAINT MONO (-6240 4410);
DISPLAY INVISIBLE (-6240 4410);
FORCEPROP 1 LASTPIN (-6250 4400) BN 11
J 0
(-6262 4408);
DISPLAY 0.489362 (-6262 4408);
PAINT GREEN (-6262 4408);
FORCEPROP 2 LAST CDS_LIB mstr_standard
J 0
(-6200 4400);
DISPLAY 0.723404 (-6200 4400);
PAINT MONO (-6200 4400);
DISPLAY INVISIBLE (-6200 4400);
FORCEPROP 1 LAST BODY_TYPE PLUMBING
J 0
(-6200 4450);
DISPLAY 0.872340 (-6200 4450);
PAINT GREEN (-6200 4450);
DISPLAY INVISIBLE (-6200 4450);
FORCEPROP 1 LAST HDL_TAP TRUE
J 0
(-5875 4275);
DISPLAY 0.872340 (-5875 4275);
DISPLAY INVISIBLE (-5875 4275);
FORCEPROP 1 LAST PATH I108
J 0
(-6202 4400);
DISPLAY 0.872340 (-6202 4400);
PAINT GREEN (-6202 4400);
DISPLAY INVISIBLE (-6202 4400);
FORCEADD TAP..1
(-6200 4450);
FORCEPROP 3 LASTPIN (-6250 4450) SIG_NAME M_C_CPU1_SA_DQ<12>
J 0
(-6240 4460);
DISPLAY 0.659574 (-6240 4460);
PAINT MONO (-6240 4460);
DISPLAY INVISIBLE (-6240 4460);
FORCEPROP 1 LASTPIN (-6250 4450) BN 12
J 0
(-6262 4458);
DISPLAY 0.489362 (-6262 4458);
PAINT GREEN (-6262 4458);
FORCEPROP 2 LAST CDS_LIB mstr_standard
J 0
(-6200 4450);
DISPLAY 0.723404 (-6200 4450);
PAINT MONO (-6200 4450);
DISPLAY INVISIBLE (-6200 4450);
FORCEPROP 1 LAST BODY_TYPE PLUMBING
J 0
(-6200 4500);
DISPLAY 0.872340 (-6200 4500);
PAINT GREEN (-6200 4500);
DISPLAY INVISIBLE (-6200 4500);
FORCEPROP 1 LAST HDL_TAP TRUE
J 0
(-5875 4325);
DISPLAY 0.872340 (-5875 4325);
DISPLAY INVISIBLE (-5875 4325);
FORCEPROP 1 LAST PATH I109
J 0
(-6202 4450);
DISPLAY 0.872340 (-6202 4450);
PAINT GREEN (-6202 4450);
DISPLAY INVISIBLE (-6202 4450);
FORCEADD OFFPAGE..6
(-8500 4050);
FORCEPROP 2 LAST $XR0 39 
J 0
(-8779 4050);
DISPLAY 0.638298 (-8779 4050);
PAINT MONO (-8779 4050);
FORCEPROP 2 LAST CDS_LIB mstr_standard
J 0
(-8500 4050);
DISPLAY 0.723404 (-8500 4050);
PAINT MONO (-8500 4050);
DISPLAY INVISIBLE (-8500 4050);
FORCEPROP 1 LAST OFFPAGE TRUE
J 0
(-8175 3925);
DISPLAY 0.872340 (-8175 3925);
PAINT GREEN (-8175 3925);
DISPLAY INVISIBLE (-8175 3925);
FORCEPROP 1 LAST COMMENT_BODY TRUE
J 0
(-8400 3975);
DISPLAY 0.872340 (-8400 3975);
PAINT GREEN (-8400 3975);
DISPLAY INVISIBLE (-8400 3975);
FORCEPROP 2 LAST PATH I11
J 0
(-8775 4100);
DISPLAY 1.021277 (-8775 4100);
DISPLAY INVISIBLE (-8775 4100);
FORCEADD TAP..1
(-6200 4550);
FORCEPROP 3 LASTPIN (-6250 4550) SIG_NAME M_C_CPU1_SA_DQ<14>
J 0
(-6240 4560);
DISPLAY 0.659574 (-6240 4560);
PAINT MONO (-6240 4560);
DISPLAY INVISIBLE (-6240 4560);
FORCEPROP 1 LASTPIN (-6250 4550) BN 14
J 0
(-6262 4558);
DISPLAY 0.489362 (-6262 4558);
PAINT GREEN (-6262 4558);
FORCEPROP 2 LAST CDS_LIB mstr_standard
J 0
(-6200 4550);
DISPLAY 0.723404 (-6200 4550);
PAINT MONO (-6200 4550);
DISPLAY INVISIBLE (-6200 4550);
FORCEPROP 1 LAST BODY_TYPE PLUMBING
J 0
(-6200 4600);
DISPLAY 0.872340 (-6200 4600);
PAINT GREEN (-6200 4600);
DISPLAY INVISIBLE (-6200 4600);
FORCEPROP 1 LAST HDL_TAP TRUE
J 0
(-5875 4425);
DISPLAY 0.872340 (-5875 4425);
DISPLAY INVISIBLE (-5875 4425);
FORCEPROP 1 LAST PATH I110
J 0
(-6202 4550);
DISPLAY 0.872340 (-6202 4550);
PAINT GREEN (-6202 4550);
DISPLAY INVISIBLE (-6202 4550);
FORCEADD TAP..1
(-6200 4600);
FORCEPROP 3 LASTPIN (-6250 4600) SIG_NAME M_C_CPU1_SA_DQ<15>
J 0
(-6240 4610);
DISPLAY 0.659574 (-6240 4610);
PAINT MONO (-6240 4610);
DISPLAY INVISIBLE (-6240 4610);
FORCEPROP 1 LASTPIN (-6250 4600) BN 15
J 0
(-6262 4608);
DISPLAY 0.489362 (-6262 4608);
PAINT GREEN (-6262 4608);
FORCEPROP 2 LAST CDS_LIB mstr_standard
J 0
(-6200 4600);
DISPLAY 0.723404 (-6200 4600);
PAINT MONO (-6200 4600);
DISPLAY INVISIBLE (-6200 4600);
FORCEPROP 1 LAST BODY_TYPE PLUMBING
J 0
(-6200 4650);
DISPLAY 0.872340 (-6200 4650);
PAINT GREEN (-6200 4650);
DISPLAY INVISIBLE (-6200 4650);
FORCEPROP 1 LAST HDL_TAP TRUE
J 0
(-5875 4475);
DISPLAY 0.872340 (-5875 4475);
DISPLAY INVISIBLE (-5875 4475);
FORCEPROP 1 LAST PATH I111
J 0
(-6202 4600);
DISPLAY 0.872340 (-6202 4600);
PAINT GREEN (-6202 4600);
DISPLAY INVISIBLE (-6202 4600);
FORCEADD TAP..1
(-6200 4500);
FORCEPROP 3 LASTPIN (-6250 4500) SIG_NAME M_C_CPU1_SA_DQ<13>
J 0
(-6240 4510);
DISPLAY 0.659574 (-6240 4510);
PAINT MONO (-6240 4510);
DISPLAY INVISIBLE (-6240 4510);
FORCEPROP 1 LASTPIN (-6250 4500) BN 13
J 0
(-6262 4508);
DISPLAY 0.489362 (-6262 4508);
PAINT GREEN (-6262 4508);
FORCEPROP 2 LAST CDS_LIB mstr_standard
J 0
(-6200 4500);
DISPLAY 0.723404 (-6200 4500);
PAINT MONO (-6200 4500);
DISPLAY INVISIBLE (-6200 4500);
FORCEPROP 1 LAST BODY_TYPE PLUMBING
J 0
(-6200 4550);
DISPLAY 0.872340 (-6200 4550);
PAINT GREEN (-6200 4550);
DISPLAY INVISIBLE (-6200 4550);
FORCEPROP 1 LAST HDL_TAP TRUE
J 0
(-5875 4375);
DISPLAY 0.872340 (-5875 4375);
DISPLAY INVISIBLE (-5875 4375);
FORCEPROP 1 LAST PATH I112
J 0
(-6202 4500);
DISPLAY 0.872340 (-6202 4500);
PAINT GREEN (-6202 4500);
DISPLAY INVISIBLE (-6202 4500);
FORCEADD TAP..1
(-6200 4650);
FORCEPROP 3 LASTPIN (-6250 4650) SIG_NAME M_C_CPU1_SA_DQ<16>
J 0
(-6240 4660);
DISPLAY 0.659574 (-6240 4660);
PAINT MONO (-6240 4660);
DISPLAY INVISIBLE (-6240 4660);
FORCEPROP 1 LASTPIN (-6250 4650) BN 16
J 0
(-6262 4658);
DISPLAY 0.489362 (-6262 4658);
PAINT GREEN (-6262 4658);
FORCEPROP 2 LAST CDS_LIB mstr_standard
J 0
(-6200 4650);
DISPLAY 0.723404 (-6200 4650);
PAINT MONO (-6200 4650);
DISPLAY INVISIBLE (-6200 4650);
FORCEPROP 1 LAST BODY_TYPE PLUMBING
J 0
(-6200 4700);
DISPLAY 0.872340 (-6200 4700);
PAINT GREEN (-6200 4700);
DISPLAY INVISIBLE (-6200 4700);
FORCEPROP 1 LAST HDL_TAP TRUE
J 0
(-5875 4525);
DISPLAY 0.872340 (-5875 4525);
DISPLAY INVISIBLE (-5875 4525);
FORCEPROP 1 LAST PATH I113
J 0
(-6202 4650);
DISPLAY 0.872340 (-6202 4650);
PAINT GREEN (-6202 4650);
DISPLAY INVISIBLE (-6202 4650);
FORCEADD TAP..1
(-6200 4700);
FORCEPROP 3 LASTPIN (-6250 4700) SIG_NAME M_C_CPU1_SA_DQ<17>
J 0
(-6240 4710);
DISPLAY 0.659574 (-6240 4710);
PAINT MONO (-6240 4710);
DISPLAY INVISIBLE (-6240 4710);
FORCEPROP 1 LASTPIN (-6250 4700) BN 17
J 0
(-6262 4708);
DISPLAY 0.489362 (-6262 4708);
PAINT GREEN (-6262 4708);
FORCEPROP 2 LAST CDS_LIB mstr_standard
J 0
(-6200 4700);
DISPLAY 0.723404 (-6200 4700);
PAINT MONO (-6200 4700);
DISPLAY INVISIBLE (-6200 4700);
FORCEPROP 1 LAST BODY_TYPE PLUMBING
J 0
(-6200 4750);
DISPLAY 0.872340 (-6200 4750);
PAINT GREEN (-6200 4750);
DISPLAY INVISIBLE (-6200 4750);
FORCEPROP 1 LAST HDL_TAP TRUE
J 0
(-5875 4575);
DISPLAY 0.872340 (-5875 4575);
DISPLAY INVISIBLE (-5875 4575);
FORCEPROP 1 LAST PATH I114
J 0
(-6202 4700);
DISPLAY 0.872340 (-6202 4700);
PAINT GREEN (-6202 4700);
DISPLAY INVISIBLE (-6202 4700);
FORCEADD TAP..1
(-6200 4850);
FORCEPROP 3 LASTPIN (-6250 4850) SIG_NAME M_C_CPU1_SA_DQ<20>
J 0
(-6240 4860);
DISPLAY 0.659574 (-6240 4860);
PAINT MONO (-6240 4860);
DISPLAY INVISIBLE (-6240 4860);
FORCEPROP 1 LASTPIN (-6250 4850) BN 20
J 0
(-6262 4858);
DISPLAY 0.489362 (-6262 4858);
PAINT GREEN (-6262 4858);
FORCEPROP 2 LAST CDS_LIB mstr_standard
J 0
(-6200 4850);
DISPLAY 0.723404 (-6200 4850);
PAINT MONO (-6200 4850);
DISPLAY INVISIBLE (-6200 4850);
FORCEPROP 1 LAST BODY_TYPE PLUMBING
J 0
(-6200 4900);
DISPLAY 0.872340 (-6200 4900);
PAINT GREEN (-6200 4900);
DISPLAY INVISIBLE (-6200 4900);
FORCEPROP 1 LAST HDL_TAP TRUE
J 0
(-5875 4725);
DISPLAY 0.872340 (-5875 4725);
DISPLAY INVISIBLE (-5875 4725);
FORCEPROP 1 LAST PATH I115
J 0
(-6202 4850);
DISPLAY 0.872340 (-6202 4850);
PAINT GREEN (-6202 4850);
DISPLAY INVISIBLE (-6202 4850);
FORCEADD TAP..1
(-6200 4800);
FORCEPROP 3 LASTPIN (-6250 4800) SIG_NAME M_C_CPU1_SA_DQ<19>
J 0
(-6240 4810);
DISPLAY 0.659574 (-6240 4810);
PAINT MONO (-6240 4810);
DISPLAY INVISIBLE (-6240 4810);
FORCEPROP 1 LASTPIN (-6250 4800) BN 19
J 0
(-6262 4808);
DISPLAY 0.489362 (-6262 4808);
PAINT GREEN (-6262 4808);
FORCEPROP 2 LAST CDS_LIB mstr_standard
J 0
(-6200 4800);
DISPLAY 0.723404 (-6200 4800);
PAINT MONO (-6200 4800);
DISPLAY INVISIBLE (-6200 4800);
FORCEPROP 1 LAST BODY_TYPE PLUMBING
J 0
(-6200 4850);
DISPLAY 0.872340 (-6200 4850);
PAINT GREEN (-6200 4850);
DISPLAY INVISIBLE (-6200 4850);
FORCEPROP 1 LAST HDL_TAP TRUE
J 0
(-5875 4675);
DISPLAY 0.872340 (-5875 4675);
DISPLAY INVISIBLE (-5875 4675);
FORCEPROP 1 LAST PATH I116
J 0
(-6202 4800);
DISPLAY 0.872340 (-6202 4800);
PAINT GREEN (-6202 4800);
DISPLAY INVISIBLE (-6202 4800);
FORCEADD TAP..1
(-6200 4750);
FORCEPROP 3 LASTPIN (-6250 4750) SIG_NAME M_C_CPU1_SA_DQ<18>
J 0
(-6240 4760);
DISPLAY 0.659574 (-6240 4760);
PAINT MONO (-6240 4760);
DISPLAY INVISIBLE (-6240 4760);
FORCEPROP 1 LASTPIN (-6250 4750) BN 18
J 0
(-6262 4758);
DISPLAY 0.489362 (-6262 4758);
PAINT GREEN (-6262 4758);
FORCEPROP 2 LAST CDS_LIB mstr_standard
J 0
(-6200 4750);
DISPLAY 0.723404 (-6200 4750);
PAINT MONO (-6200 4750);
DISPLAY INVISIBLE (-6200 4750);
FORCEPROP 1 LAST BODY_TYPE PLUMBING
J 0
(-6200 4800);
DISPLAY 0.872340 (-6200 4800);
PAINT GREEN (-6200 4800);
DISPLAY INVISIBLE (-6200 4800);
FORCEPROP 1 LAST HDL_TAP TRUE
J 0
(-5875 4625);
DISPLAY 0.872340 (-5875 4625);
DISPLAY INVISIBLE (-5875 4625);
FORCEPROP 1 LAST PATH I117
J 0
(-6202 4750);
DISPLAY 0.872340 (-6202 4750);
PAINT GREEN (-6202 4750);
DISPLAY INVISIBLE (-6202 4750);
FORCEADD TAP..1
(-6200 4900);
FORCEPROP 3 LASTPIN (-6250 4900) SIG_NAME M_C_CPU1_SA_DQ<21>
J 0
(-6240 4910);
DISPLAY 0.659574 (-6240 4910);
PAINT MONO (-6240 4910);
DISPLAY INVISIBLE (-6240 4910);
FORCEPROP 1 LASTPIN (-6250 4900) BN 21
J 0
(-6262 4908);
DISPLAY 0.489362 (-6262 4908);
PAINT GREEN (-6262 4908);
FORCEPROP 2 LAST CDS_LIB mstr_standard
J 0
(-6200 4900);
DISPLAY 0.723404 (-6200 4900);
PAINT MONO (-6200 4900);
DISPLAY INVISIBLE (-6200 4900);
FORCEPROP 1 LAST BODY_TYPE PLUMBING
J 0
(-6200 4950);
DISPLAY 0.872340 (-6200 4950);
PAINT GREEN (-6200 4950);
DISPLAY INVISIBLE (-6200 4950);
FORCEPROP 1 LAST HDL_TAP TRUE
J 0
(-5875 4775);
DISPLAY 0.872340 (-5875 4775);
DISPLAY INVISIBLE (-5875 4775);
FORCEPROP 1 LAST PATH I118
J 0
(-6202 4900);
DISPLAY 0.872340 (-6202 4900);
PAINT GREEN (-6202 4900);
DISPLAY INVISIBLE (-6202 4900);
FORCEADD TAP..1
(-6200 4950);
FORCEPROP 3 LASTPIN (-6250 4950) SIG_NAME M_C_CPU1_SA_DQ<22>
J 0
(-6240 4960);
DISPLAY 0.659574 (-6240 4960);
PAINT MONO (-6240 4960);
DISPLAY INVISIBLE (-6240 4960);
FORCEPROP 1 LASTPIN (-6250 4950) BN 22
J 0
(-6262 4958);
DISPLAY 0.489362 (-6262 4958);
PAINT GREEN (-6262 4958);
FORCEPROP 2 LAST CDS_LIB mstr_standard
J 0
(-6200 4950);
DISPLAY 0.723404 (-6200 4950);
PAINT MONO (-6200 4950);
DISPLAY INVISIBLE (-6200 4950);
FORCEPROP 1 LAST BODY_TYPE PLUMBING
J 0
(-6200 5000);
DISPLAY 0.872340 (-6200 5000);
PAINT GREEN (-6200 5000);
DISPLAY INVISIBLE (-6200 5000);
FORCEPROP 1 LAST HDL_TAP TRUE
J 0
(-5875 4825);
DISPLAY 0.872340 (-5875 4825);
DISPLAY INVISIBLE (-5875 4825);
FORCEPROP 1 LAST PATH I119
J 0
(-6202 4950);
DISPLAY 0.872340 (-6202 4950);
PAINT GREEN (-6202 4950);
DISPLAY INVISIBLE (-6202 4950);
FORCEADD OFFPAGE..1
(-8500 4100);
FORCEPROP 2 LAST $XR0 39 
J 0
(-8721 4100);
DISPLAY 0.638298 (-8721 4100);
PAINT MONO (-8721 4100);
FORCEPROP 2 LAST CDS_LIB mstr_standard
J 0
(-8500 4100);
DISPLAY 0.808511 (-8500 4100);
DISPLAY INVISIBLE (-8500 4100);
FORCEPROP 1 LAST OFFPAGE TRUE
J 0
(-8175 3975);
DISPLAY 0.872340 (-8175 3975);
PAINT GREEN (-8175 3975);
DISPLAY INVISIBLE (-8175 3975);
FORCEPROP 1 LAST COMMENT_BODY TRUE
J 0
(-8375 4000);
DISPLAY 0.872340 (-8375 4000);
PAINT GREEN (-8375 4000);
DISPLAY INVISIBLE (-8375 4000);
FORCEPROP 2 LAST PATH I12
J 0
(-8700 4150);
DISPLAY 1.021277 (-8700 4150);
DISPLAY INVISIBLE (-8700 4150);
FORCEADD TAP..1
(-6200 5000);
FORCEPROP 3 LASTPIN (-6250 5000) SIG_NAME M_C_CPU1_SA_DQ<23>
J 0
(-6240 5010);
DISPLAY 0.659574 (-6240 5010);
PAINT MONO (-6240 5010);
DISPLAY INVISIBLE (-6240 5010);
FORCEPROP 1 LASTPIN (-6250 5000) BN 23
J 0
(-6262 5008);
DISPLAY 0.489362 (-6262 5008);
PAINT GREEN (-6262 5008);
FORCEPROP 2 LAST CDS_LIB mstr_standard
J 0
(-6200 5000);
DISPLAY 0.723404 (-6200 5000);
PAINT MONO (-6200 5000);
DISPLAY INVISIBLE (-6200 5000);
FORCEPROP 1 LAST BODY_TYPE PLUMBING
J 0
(-6200 5050);
DISPLAY 0.872340 (-6200 5050);
PAINT GREEN (-6200 5050);
DISPLAY INVISIBLE (-6200 5050);
FORCEPROP 1 LAST HDL_TAP TRUE
J 0
(-5875 4875);
DISPLAY 0.872340 (-5875 4875);
DISPLAY INVISIBLE (-5875 4875);
FORCEPROP 1 LAST PATH I120
J 0
(-6202 5000);
DISPLAY 0.872340 (-6202 5000);
PAINT GREEN (-6202 5000);
DISPLAY INVISIBLE (-6202 5000);
FORCEADD TAP..1
(-6200 5050);
FORCEPROP 3 LASTPIN (-6250 5050) SIG_NAME M_C_CPU1_SA_DQ<24>
J 0
(-6240 5060);
DISPLAY 0.659574 (-6240 5060);
PAINT MONO (-6240 5060);
DISPLAY INVISIBLE (-6240 5060);
FORCEPROP 1 LASTPIN (-6250 5050) BN 24
J 0
(-6262 5058);
DISPLAY 0.489362 (-6262 5058);
PAINT GREEN (-6262 5058);
FORCEPROP 2 LAST CDS_LIB mstr_standard
J 0
(-6200 5050);
DISPLAY 0.723404 (-6200 5050);
PAINT MONO (-6200 5050);
DISPLAY INVISIBLE (-6200 5050);
FORCEPROP 1 LAST BODY_TYPE PLUMBING
J 0
(-6200 5100);
DISPLAY 0.872340 (-6200 5100);
PAINT GREEN (-6200 5100);
DISPLAY INVISIBLE (-6200 5100);
FORCEPROP 1 LAST HDL_TAP TRUE
J 0
(-5875 4925);
DISPLAY 0.872340 (-5875 4925);
DISPLAY INVISIBLE (-5875 4925);
FORCEPROP 1 LAST PATH I121
J 0
(-6202 5050);
DISPLAY 0.872340 (-6202 5050);
PAINT GREEN (-6202 5050);
DISPLAY INVISIBLE (-6202 5050);
FORCEADD TAP..1
(-6200 5100);
FORCEPROP 3 LASTPIN (-6250 5100) SIG_NAME M_C_CPU1_SA_DQ<25>
J 0
(-6240 5110);
DISPLAY 0.659574 (-6240 5110);
PAINT MONO (-6240 5110);
DISPLAY INVISIBLE (-6240 5110);
FORCEPROP 1 LASTPIN (-6250 5100) BN 25
J 0
(-6262 5108);
DISPLAY 0.489362 (-6262 5108);
PAINT GREEN (-6262 5108);
FORCEPROP 2 LAST CDS_LIB mstr_standard
J 0
(-6200 5100);
DISPLAY 0.723404 (-6200 5100);
PAINT MONO (-6200 5100);
DISPLAY INVISIBLE (-6200 5100);
FORCEPROP 1 LAST BODY_TYPE PLUMBING
J 0
(-6200 5150);
DISPLAY 0.872340 (-6200 5150);
PAINT GREEN (-6200 5150);
DISPLAY INVISIBLE (-6200 5150);
FORCEPROP 1 LAST HDL_TAP TRUE
J 0
(-5875 4975);
DISPLAY 0.872340 (-5875 4975);
DISPLAY INVISIBLE (-5875 4975);
FORCEPROP 1 LAST PATH I122
J 0
(-6202 5100);
DISPLAY 0.872340 (-6202 5100);
PAINT GREEN (-6202 5100);
DISPLAY INVISIBLE (-6202 5100);
FORCEADD TAP..1
(-6200 5250);
FORCEPROP 3 LASTPIN (-6250 5250) SIG_NAME M_C_CPU1_SA_DQ<28>
J 0
(-6240 5260);
DISPLAY 0.659574 (-6240 5260);
PAINT MONO (-6240 5260);
DISPLAY INVISIBLE (-6240 5260);
FORCEPROP 1 LASTPIN (-6250 5250) BN 28
J 0
(-6262 5258);
DISPLAY 0.489362 (-6262 5258);
PAINT GREEN (-6262 5258);
FORCEPROP 2 LAST CDS_LIB mstr_standard
J 0
(-6200 5250);
DISPLAY 0.723404 (-6200 5250);
PAINT MONO (-6200 5250);
DISPLAY INVISIBLE (-6200 5250);
FORCEPROP 1 LAST BODY_TYPE PLUMBING
J 0
(-6200 5300);
DISPLAY 0.872340 (-6200 5300);
PAINT GREEN (-6200 5300);
DISPLAY INVISIBLE (-6200 5300);
FORCEPROP 1 LAST HDL_TAP TRUE
J 0
(-5875 5125);
DISPLAY 0.872340 (-5875 5125);
DISPLAY INVISIBLE (-5875 5125);
FORCEPROP 1 LAST PATH I123
J 0
(-6202 5250);
DISPLAY 0.872340 (-6202 5250);
PAINT GREEN (-6202 5250);
DISPLAY INVISIBLE (-6202 5250);
FORCEADD TAP..1
(-6200 5200);
FORCEPROP 3 LASTPIN (-6250 5200) SIG_NAME M_C_CPU1_SA_DQ<27>
J 0
(-6240 5210);
DISPLAY 0.659574 (-6240 5210);
PAINT MONO (-6240 5210);
DISPLAY INVISIBLE (-6240 5210);
FORCEPROP 1 LASTPIN (-6250 5200) BN 27
J 0
(-6262 5208);
DISPLAY 0.489362 (-6262 5208);
PAINT GREEN (-6262 5208);
FORCEPROP 2 LAST CDS_LIB mstr_standard
J 0
(-6200 5200);
DISPLAY 0.723404 (-6200 5200);
PAINT MONO (-6200 5200);
DISPLAY INVISIBLE (-6200 5200);
FORCEPROP 1 LAST BODY_TYPE PLUMBING
J 0
(-6200 5250);
DISPLAY 0.872340 (-6200 5250);
PAINT GREEN (-6200 5250);
DISPLAY INVISIBLE (-6200 5250);
FORCEPROP 1 LAST HDL_TAP TRUE
J 0
(-5875 5075);
DISPLAY 0.872340 (-5875 5075);
DISPLAY INVISIBLE (-5875 5075);
FORCEPROP 1 LAST PATH I124
J 0
(-6202 5200);
DISPLAY 0.872340 (-6202 5200);
PAINT GREEN (-6202 5200);
DISPLAY INVISIBLE (-6202 5200);
FORCEADD TAP..1
(-6200 5150);
FORCEPROP 3 LASTPIN (-6250 5150) SIG_NAME M_C_CPU1_SA_DQ<26>
J 0
(-6240 5160);
DISPLAY 0.659574 (-6240 5160);
PAINT MONO (-6240 5160);
DISPLAY INVISIBLE (-6240 5160);
FORCEPROP 1 LASTPIN (-6250 5150) BN 26
J 0
(-6262 5158);
DISPLAY 0.489362 (-6262 5158);
PAINT GREEN (-6262 5158);
FORCEPROP 2 LAST CDS_LIB mstr_standard
J 0
(-6200 5150);
DISPLAY 0.723404 (-6200 5150);
PAINT MONO (-6200 5150);
DISPLAY INVISIBLE (-6200 5150);
FORCEPROP 1 LAST BODY_TYPE PLUMBING
J 0
(-6200 5200);
DISPLAY 0.872340 (-6200 5200);
PAINT GREEN (-6200 5200);
DISPLAY INVISIBLE (-6200 5200);
FORCEPROP 1 LAST HDL_TAP TRUE
J 0
(-5875 5025);
DISPLAY 0.872340 (-5875 5025);
DISPLAY INVISIBLE (-5875 5025);
FORCEPROP 1 LAST PATH I125
J 0
(-6202 5150);
DISPLAY 0.872340 (-6202 5150);
PAINT GREEN (-6202 5150);
DISPLAY INVISIBLE (-6202 5150);
FORCEADD TAP..1
(-6200 5300);
FORCEPROP 3 LASTPIN (-6250 5300) SIG_NAME M_C_CPU1_SA_DQ<29>
J 0
(-6240 5310);
DISPLAY 0.659574 (-6240 5310);
PAINT MONO (-6240 5310);
DISPLAY INVISIBLE (-6240 5310);
FORCEPROP 1 LASTPIN (-6250 5300) BN 29
J 0
(-6262 5308);
DISPLAY 0.489362 (-6262 5308);
PAINT GREEN (-6262 5308);
FORCEPROP 2 LAST CDS_LIB mstr_standard
J 0
(-6200 5300);
DISPLAY 0.723404 (-6200 5300);
PAINT MONO (-6200 5300);
DISPLAY INVISIBLE (-6200 5300);
FORCEPROP 1 LAST BODY_TYPE PLUMBING
J 0
(-6200 5350);
DISPLAY 0.872340 (-6200 5350);
PAINT GREEN (-6200 5350);
DISPLAY INVISIBLE (-6200 5350);
FORCEPROP 1 LAST HDL_TAP TRUE
J 0
(-5875 5175);
DISPLAY 0.872340 (-5875 5175);
DISPLAY INVISIBLE (-5875 5175);
FORCEPROP 1 LAST PATH I126
J 0
(-6202 5300);
DISPLAY 0.872340 (-6202 5300);
PAINT GREEN (-6202 5300);
DISPLAY INVISIBLE (-6202 5300);
FORCEADD TAP..1
(-6200 5350);
FORCEPROP 3 LASTPIN (-6250 5350) SIG_NAME M_C_CPU1_SA_DQ<30>
J 0
(-6240 5360);
DISPLAY 0.659574 (-6240 5360);
PAINT MONO (-6240 5360);
DISPLAY INVISIBLE (-6240 5360);
FORCEPROP 1 LASTPIN (-6250 5350) BN 30
J 0
(-6262 5358);
DISPLAY 0.489362 (-6262 5358);
PAINT GREEN (-6262 5358);
FORCEPROP 2 LAST CDS_LIB mstr_standard
J 0
(-6200 5350);
DISPLAY 0.723404 (-6200 5350);
PAINT MONO (-6200 5350);
DISPLAY INVISIBLE (-6200 5350);
FORCEPROP 1 LAST BODY_TYPE PLUMBING
J 0
(-6200 5400);
DISPLAY 0.872340 (-6200 5400);
PAINT GREEN (-6200 5400);
DISPLAY INVISIBLE (-6200 5400);
FORCEPROP 1 LAST HDL_TAP TRUE
J 0
(-5875 5225);
DISPLAY 0.872340 (-5875 5225);
DISPLAY INVISIBLE (-5875 5225);
FORCEPROP 1 LAST PATH I127
J 0
(-6202 5350);
DISPLAY 0.872340 (-6202 5350);
PAINT GREEN (-6202 5350);
DISPLAY INVISIBLE (-6202 5350);
FORCEADD TAP..1
(-6200 5400);
FORCEPROP 3 LASTPIN (-6250 5400) SIG_NAME M_C_CPU1_SA_DQ<31>
J 0
(-6240 5410);
DISPLAY 0.659574 (-6240 5410);
PAINT MONO (-6240 5410);
DISPLAY INVISIBLE (-6240 5410);
FORCEPROP 1 LASTPIN (-6250 5400) BN 31
J 0
(-6262 5408);
DISPLAY 0.489362 (-6262 5408);
PAINT GREEN (-6262 5408);
FORCEPROP 2 LAST CDS_LIB mstr_standard
J 0
(-6200 5400);
DISPLAY 0.723404 (-6200 5400);
PAINT MONO (-6200 5400);
DISPLAY INVISIBLE (-6200 5400);
FORCEPROP 1 LAST BODY_TYPE PLUMBING
J 0
(-6200 5450);
DISPLAY 0.872340 (-6200 5450);
PAINT GREEN (-6200 5450);
DISPLAY INVISIBLE (-6200 5450);
FORCEPROP 1 LAST HDL_TAP TRUE
J 0
(-5875 5275);
DISPLAY 0.872340 (-5875 5275);
DISPLAY INVISIBLE (-5875 5275);
FORCEPROP 1 LAST PATH I128
J 0
(-6202 5400);
DISPLAY 0.872340 (-6202 5400);
PAINT GREEN (-6202 5400);
DISPLAY INVISIBLE (-6202 5400);
FORCEADD OFFPAGE..3
(-5600 5450);
FORCEPROP 2 LAST $XR0 39 
J 0
(-5386 5450);
DISPLAY 0.638298 (-5386 5450);
PAINT MONO (-5386 5450);
FORCEPROP 2 LAST CDS_LIB mstr_standard
J 0
(-5600 5450);
DISPLAY 0.723404 (-5600 5450);
PAINT MONO (-5600 5450);
DISPLAY INVISIBLE (-5600 5450);
FORCEPROP 1 LAST OFFPAGE TRUE
J 0
(-5275 5325);
DISPLAY 0.872340 (-5275 5325);
PAINT GREEN (-5275 5325);
DISPLAY INVISIBLE (-5275 5325);
FORCEPROP 1 LAST COMMENT_BODY TRUE
J 0
(-5650 5350);
DISPLAY 0.872340 (-5650 5350);
PAINT GREEN (-5650 5350);
DISPLAY INVISIBLE (-5650 5350);
FORCEPROP 2 LAST PATH I129
J 0
(-5375 5500);
DISPLAY 1.021277 (-5375 5500);
DISPLAY INVISIBLE (-5375 5500);
FORCEADD OFFPAGE..1
(-8500 4300);
FORCEPROP 2 LAST $XR0 39 
J 0
(-8721 4300);
DISPLAY 0.638298 (-8721 4300);
PAINT MONO (-8721 4300);
FORCEPROP 2 LAST CDS_LIB mstr_standard
J 0
(-8500 4300);
DISPLAY 0.723404 (-8500 4300);
PAINT MONO (-8500 4300);
DISPLAY INVISIBLE (-8500 4300);
FORCEPROP 1 LAST OFFPAGE TRUE
J 0
(-8175 4175);
DISPLAY 0.872340 (-8175 4175);
PAINT GREEN (-8175 4175);
DISPLAY INVISIBLE (-8175 4175);
FORCEPROP 1 LAST COMMENT_BODY TRUE
J 0
(-8375 4200);
DISPLAY 0.872340 (-8375 4200);
PAINT GREEN (-8375 4200);
DISPLAY INVISIBLE (-8375 4200);
FORCEPROP 2 LAST PATH I13
J 0
(-8700 4350);
DISPLAY 1.021277 (-8700 4350);
DISPLAY INVISIBLE (-8700 4350);
FORCEADD OFFPAGE..1
(-8500 4250);
FORCEPROP 2 LAST $XR0 39 
J 0
(-8721 4250);
DISPLAY 0.638298 (-8721 4250);
PAINT MONO (-8721 4250);
FORCEPROP 2 LAST CDS_LIB mstr_standard
J 0
(-8500 4250);
DISPLAY 0.808511 (-8500 4250);
DISPLAY INVISIBLE (-8500 4250);
FORCEPROP 1 LAST OFFPAGE TRUE
J 0
(-8175 4125);
DISPLAY 0.872340 (-8175 4125);
PAINT GREEN (-8175 4125);
DISPLAY INVISIBLE (-8175 4125);
FORCEPROP 1 LAST COMMENT_BODY TRUE
J 0
(-8375 4150);
DISPLAY 0.872340 (-8375 4150);
PAINT GREEN (-8375 4150);
DISPLAY INVISIBLE (-8375 4150);
FORCEPROP 2 LAST PATH I14
J 0
(-8700 4300);
DISPLAY 1.021277 (-8700 4300);
DISPLAY INVISIBLE (-8700 4300);
FORCEADD OFFPAGE..5
(-7375 1425);
FORCEPROP 2 LAST $XR0 100 
J 0
(-7660 1425);
DISPLAY 0.638298 (-7660 1425);
PAINT MONO (-7660 1425);
FORCEPROP 2 LAST BOM_COST MEM
J 0
(-7450 1500);
DISPLAY 0.808511 (-7450 1500);
DISPLAY INVISIBLE (-7450 1500);
FORCEPROP 2 LAST CDS_LIB mstr_standard
J 0
(-7375 1425);
DISPLAY 0.808511 (-7375 1425);
DISPLAY INVISIBLE (-7375 1425);
FORCEPROP 1 LAST OFFPAGE TRUE
J 0
(-7050 1300);
DISPLAY 0.872340 (-7050 1300);
PAINT GREEN (-7050 1300);
DISPLAY INVISIBLE (-7050 1300);
FORCEPROP 1 LAST COMMENT_BODY TRUE
J 0
(-7275 1350);
DISPLAY 0.872340 (-7275 1350);
PAINT GREEN (-7275 1350);
DISPLAY INVISIBLE (-7275 1350);
FORCEPROP 2 LAST PATH I146
J 0
(-7625 1475);
DISPLAY 1.021277 (-7625 1475);
DISPLAY INVISIBLE (-7625 1475);
FORCEADD GND..1
(-6600 1025);
FORCEPROP 3 LASTPIN (-6600 1075) SIG_NAME GND\g
J 0
(-6590 1085);
DISPLAY 0.659574 (-6590 1085);
PAINT MONO (-6590 1085);
DISPLAY INVISIBLE (-6590 1085);
FORCEPROP 1 LAST SIZE 1B
J 0
(-6525 975);
DISPLAY 0.851064 (-6525 975);
PAINT GREEN (-6525 975);
DISPLAY INVISIBLE (-6525 975);
FORCEPROP 2 LAST BOM_COST MEM
J 0
(-6700 1100);
DISPLAY 0.808511 (-6700 1100);
DISPLAY INVISIBLE (-6700 1100);
FORCEPROP 2 LAST CDS_LIB mstr_symbols
J 0
(-6600 1025);
DISPLAY 0.808511 (-6600 1025);
DISPLAY INVISIBLE (-6600 1025);
FORCEPROP 1 LAST VOLTAGE 0.0
J 0
(-6645 982);
DISPLAY 0.723404 (-6645 982);
PAINT SKYBLUE (-6645 982);
DISPLAY INVISIBLE (-6645 982);
FORCEPROP 1 LAST BODY_TYPE PLUMBING
J 0
(-6645 982);
DISPLAY 0.340426 (-6645 982);
PAINT GREEN (-6645 982);
DISPLAY INVISIBLE (-6645 982);
FORCEPROP 1 LAST HDL_POWER GND
J 0
(-6600 1175);
DISPLAY 0.851064 (-6600 1175);
PAINT GREEN (-6600 1175);
DISPLAY INVISIBLE (-6600 1175);
FORCEPROP 1 LAST PATH I147
J 0
(-6525 1025);
DISPLAY 0.872340 (-6525 1025);
PAINT AQUA (-6525 1025);
DISPLAY INVISIBLE (-6525 1025);
FORCEADD Q_RES..2
(-6600 1250);
FORCEPROP 1 LAST LOCATION R771
J 0
(-6555 1375);
DISPLAY 0.489362 (-6555 1375);
PAINT SKYBLUE (-6555 1375);
FORCEPROP 0 LAST $SEC 1
J 0
(-6550 1425);
DISPLAY 0.680851 (-6550 1425);
PAINT MONO (-6550 1425);
DISPLAY INVISIBLE (-6550 1425);
FORCEPROP 0 LAST CDS_SEC 1
J 0
(-6550 1425);
DISPLAY 1.021277 (-6550 1425);
DISPLAY INVISIBLE (-6550 1425);
FORCEPROP 1 LASTPIN (-6600 1350) $PN 1
J 0
(-6595 1312);
DISPLAY 0.489362 (-6595 1312);
PAINT MONO (-6595 1312);
FORCEPROP 1 LASTPIN (-6600 1150) $PN 2
J 0
(-6595 1160);
DISPLAY 0.489362 (-6595 1160);
PAINT MONO (-6595 1160);
FORCEPROP 1 LAST PACK_TYPE 0402LF
J 0
(-6560 1075);
DISPLAY 0.489362 (-6560 1075);
PAINT SKYBLUE (-6560 1075);
FORCEPROP 1 LAST VALUE 23.2K
J 0
(-6555 1325);
DISPLAY 0.489362 (-6555 1325);
PAINT SKYBLUE (-6555 1325);
FORCEPROP 1 LAST TOLERANCE 1%
J 0
(-6555 1275);
DISPLAY 0.489362 (-6555 1275);
PAINT SKYBLUE (-6555 1275);
FORCEPROP 1 LAST MATERIAL CHIP
J 0
(-6560 1175);
DISPLAY 0.489362 (-6560 1175);
PAINT SKYBLUE (-6560 1175);
FORCEPROP 1 LAST WATTAGE 1/16W
J 0
(-6560 1225);
DISPLAY 0.489362 (-6560 1225);
PAINT SKYBLUE (-6560 1225);
FORCEPROP 2 LAST CDS_LIB pure_quanta
J 0
(-6600 1250);
DISPLAY INVISIBLE (-6600 1250);
FORCEPROP 1 LAST PATH I148
J 0
(-6550 1425);
DISPLAY 0.978723 (-6550 1425);
PAINT WHITE (-6550 1425);
DISPLAY INVISIBLE (-6550 1425);
FORCEPROP 1 LAST PART_NUMBER CS32322FB03
J 0
(-6560 1125);
DISPLAY 0.489362 (-6560 1125);
PAINT SKYBLUE (-6560 1125);
DISPLAY INVISIBLE (-6560 1125);
FORCEADD OFFPAGE..1
(-8500 4150);
FORCEPROP 2 LAST $XR0 39 
J 0
(-8721 4150);
DISPLAY 0.638298 (-8721 4150);
PAINT MONO (-8721 4150);
FORCEPROP 2 LAST CDS_LIB mstr_standard
J 0
(-8500 4150);
DISPLAY 0.723404 (-8500 4150);
PAINT MONO (-8500 4150);
DISPLAY INVISIBLE (-8500 4150);
FORCEPROP 1 LAST OFFPAGE TRUE
J 0
(-8175 4025);
DISPLAY 0.872340 (-8175 4025);
PAINT GREEN (-8175 4025);
DISPLAY INVISIBLE (-8175 4025);
FORCEPROP 1 LAST COMMENT_BODY TRUE
J 0
(-8375 4050);
DISPLAY 0.872340 (-8375 4050);
PAINT GREEN (-8375 4050);
DISPLAY INVISIBLE (-8375 4050);
FORCEPROP 2 LAST PATH I15
J 0
(-8700 4200);
DISPLAY 1.021277 (-8700 4200);
DISPLAY INVISIBLE (-8700 4200);
FORCEADD GND..1
(-2225 2000);
FORCEPROP 3 LASTPIN (-2225 2050) SIG_NAME GND\g
J 0
(-2215 2060);
DISPLAY 0.659574 (-2215 2060);
PAINT MONO (-2215 2060);
DISPLAY INVISIBLE (-2215 2060);
FORCEPROP 1 LAST SIZE 1B
J 0
(-2150 1950);
DISPLAY 0.851064 (-2150 1950);
PAINT GREEN (-2150 1950);
DISPLAY INVISIBLE (-2150 1950);
FORCEPROP 2 LAST CDS_LIB mstr_symbols
J 0
(-2225 2000);
DISPLAY 0.723404 (-2225 2000);
DISPLAY INVISIBLE (-2225 2000);
FORCEPROP 1 LAST VOLTAGE 0.0
J 0
(-2270 1957);
DISPLAY 0.723404 (-2270 1957);
PAINT SKYBLUE (-2270 1957);
DISPLAY INVISIBLE (-2270 1957);
FORCEPROP 1 LAST BODY_TYPE PLUMBING
J 0
(-2270 1957);
DISPLAY 0.340426 (-2270 1957);
PAINT GREEN (-2270 1957);
DISPLAY INVISIBLE (-2270 1957);
FORCEPROP 1 LAST HDL_POWER GND
J 0
(-2225 2150);
DISPLAY 0.851064 (-2225 2150);
PAINT GREEN (-2225 2150);
DISPLAY INVISIBLE (-2225 2150);
FORCEPROP 1 LAST PATH I154
J 0
(-2150 2000);
DISPLAY 0.872340 (-2150 2000);
PAINT AQUA (-2150 2000);
DISPLAY INVISIBLE (-2150 2000);
FORCEADD SCONN288_DDR506112002KQ..3
(-1325 3750);
FORCEPROP 1 LAST LOCATION J28
J 0
(-1775 5725);
DISPLAY 0.468085 (-1775 5725);
PAINT SKYBLUE (-1775 5725);
FORCEPROP 0 LAST $SEC 3
J 0
(-1775 5875);
DISPLAY 0.680851 (-1775 5875);
PAINT MONO (-1775 5875);
DISPLAY INVISIBLE (-1775 5875);
FORCEPROP 2 LAST CDS_SEC 3
J 0
(-1775 5875);
DISPLAY 1.021277 (-1775 5875);
DISPLAY INVISIBLE (-1775 5875);
FORCEPROP 0 LASTPIN (-725 2150) $PN G1
J 0
(-715 2160);
DISPLAY 0.680851 (-715 2160);
PAINT MONO (-715 2160);
FORCEPROP 0 LASTPIN (-725 2100) $PN G2
J 0
(-715 2110);
DISPLAY 0.680851 (-715 2110);
PAINT MONO (-715 2110);
FORCEPROP 0 LASTPIN (-725 2050) $PN G3
J 0
(-715 2060);
DISPLAY 0.680851 (-715 2060);
PAINT MONO (-715 2060);
FORCEPROP 0 LASTPIN (-1925 5300) $PN 1
J 2
(-1935 5310);
DISPLAY 0.680851 (-1935 5310);
PAINT MONO (-1935 5310);
FORCEPROP 0 LASTPIN (-1925 5350) $PN 145
J 2
(-1935 5360);
DISPLAY 0.680851 (-1935 5360);
PAINT MONO (-1935 5360);
FORCEPROP 0 LASTPIN (-1925 5400) $PN 146
J 2
(-1935 5410);
DISPLAY 0.680851 (-1935 5410);
PAINT MONO (-1935 5410);
FORCEPROP 0 LASTPIN (-725 2250) $PN 6
J 0
(-715 2260);
DISPLAY 0.680851 (-715 2260);
PAINT MONO (-715 2260);
FORCEPROP 0 LASTPIN (-725 2300) $PN 8
J 0
(-715 2310);
DISPLAY 0.680851 (-715 2310);
PAINT MONO (-715 2310);
FORCEPROP 0 LASTPIN (-725 2350) $PN 10
J 0
(-715 2360);
DISPLAY 0.680851 (-715 2360);
PAINT MONO (-715 2360);
FORCEPROP 0 LASTPIN (-725 2400) $PN 13
J 0
(-715 2410);
DISPLAY 0.680851 (-715 2410);
PAINT MONO (-715 2410);
FORCEPROP 0 LASTPIN (-725 2450) $PN 15
J 0
(-715 2460);
DISPLAY 0.680851 (-715 2460);
PAINT MONO (-715 2460);
FORCEPROP 0 LASTPIN (-725 2500) $PN 17
J 0
(-715 2510);
DISPLAY 0.680851 (-715 2510);
PAINT MONO (-715 2510);
FORCEPROP 0 LASTPIN (-725 2550) $PN 19
J 0
(-715 2560);
DISPLAY 0.680851 (-715 2560);
PAINT MONO (-715 2560);
FORCEPROP 0 LASTPIN (-725 2600) $PN 21
J 0
(-715 2610);
DISPLAY 0.680851 (-715 2610);
PAINT MONO (-715 2610);
FORCEPROP 0 LASTPIN (-725 2650) $PN 24
J 0
(-715 2660);
DISPLAY 0.680851 (-715 2660);
PAINT MONO (-715 2660);
FORCEPROP 0 LASTPIN (-725 2700) $PN 26
J 0
(-715 2710);
DISPLAY 0.680851 (-715 2710);
PAINT MONO (-715 2710);
FORCEPROP 0 LASTPIN (-725 2750) $PN 28
J 0
(-715 2760);
DISPLAY 0.680851 (-715 2760);
PAINT MONO (-715 2760);
FORCEPROP 0 LASTPIN (-725 2800) $PN 30
J 0
(-715 2810);
DISPLAY 0.680851 (-715 2810);
PAINT MONO (-715 2810);
FORCEPROP 0 LASTPIN (-725 2850) $PN 32
J 0
(-715 2860);
DISPLAY 0.680851 (-715 2860);
PAINT MONO (-715 2860);
FORCEPROP 0 LASTPIN (-725 2900) $PN 35
J 0
(-715 2910);
DISPLAY 0.680851 (-715 2910);
PAINT MONO (-715 2910);
FORCEPROP 0 LASTPIN (-725 2950) $PN 37
J 0
(-715 2960);
DISPLAY 0.680851 (-715 2960);
PAINT MONO (-715 2960);
FORCEPROP 0 LASTPIN (-725 3000) $PN 39
J 0
(-715 3010);
DISPLAY 0.680851 (-715 3010);
PAINT MONO (-715 3010);
FORCEPROP 0 LASTPIN (-725 3050) $PN 41
J 0
(-715 3060);
DISPLAY 0.680851 (-715 3060);
PAINT MONO (-715 3060);
FORCEPROP 0 LASTPIN (-725 3100) $PN 43
J 0
(-715 3110);
DISPLAY 0.680851 (-715 3110);
PAINT MONO (-715 3110);
FORCEPROP 0 LASTPIN (-725 3150) $PN 46
J 0
(-715 3160);
DISPLAY 0.680851 (-715 3160);
PAINT MONO (-715 3160);
FORCEPROP 0 LASTPIN (-725 3200) $PN 48
J 0
(-715 3210);
DISPLAY 0.680851 (-715 3210);
PAINT MONO (-715 3210);
FORCEPROP 0 LASTPIN (-725 3250) $PN 50
J 0
(-715 3260);
DISPLAY 0.680851 (-715 3260);
PAINT MONO (-715 3260);
FORCEPROP 0 LASTPIN (-725 3300) $PN 52
J 0
(-715 3310);
DISPLAY 0.680851 (-715 3310);
PAINT MONO (-715 3310);
FORCEPROP 0 LASTPIN (-725 3350) $PN 54
J 0
(-715 3360);
DISPLAY 0.680851 (-715 3360);
PAINT MONO (-715 3360);
FORCEPROP 0 LASTPIN (-725 3400) $PN 57
J 0
(-715 3410);
DISPLAY 0.680851 (-715 3410);
PAINT MONO (-715 3410);
FORCEPROP 0 LASTPIN (-725 3450) $PN 59
J 0
(-715 3460);
DISPLAY 0.680851 (-715 3460);
PAINT MONO (-715 3460);
FORCEPROP 0 LASTPIN (-725 3500) $PN 61
J 0
(-715 3510);
DISPLAY 0.680851 (-715 3510);
PAINT MONO (-715 3510);
FORCEPROP 0 LASTPIN (-725 3550) $PN 63
J 0
(-715 3560);
DISPLAY 0.680851 (-715 3560);
PAINT MONO (-715 3560);
FORCEPROP 0 LASTPIN (-725 3600) $PN 65
J 0
(-715 3610);
DISPLAY 0.680851 (-715 3610);
PAINT MONO (-715 3610);
FORCEPROP 0 LASTPIN (-725 3650) $PN 67
J 0
(-715 3660);
DISPLAY 0.680851 (-715 3660);
PAINT MONO (-715 3660);
FORCEPROP 0 LASTPIN (-725 3700) $PN 69
J 0
(-715 3710);
DISPLAY 0.680851 (-715 3710);
PAINT MONO (-715 3710);
FORCEPROP 0 LASTPIN (-725 3750) $PN 71
J 0
(-715 3760);
DISPLAY 0.680851 (-715 3760);
PAINT MONO (-715 3760);
FORCEPROP 0 LASTPIN (-725 3800) $PN 73
J 0
(-715 3810);
DISPLAY 0.680851 (-715 3810);
PAINT MONO (-715 3810);
FORCEPROP 0 LASTPIN (-725 3850) $PN 75
J 0
(-715 3860);
DISPLAY 0.680851 (-715 3860);
PAINT MONO (-715 3860);
FORCEPROP 0 LASTPIN (-725 3900) $PN 77
J 0
(-715 3910);
DISPLAY 0.680851 (-715 3910);
PAINT MONO (-715 3910);
FORCEPROP 0 LASTPIN (-725 3950) $PN 79
J 0
(-715 3960);
DISPLAY 0.680851 (-715 3960);
PAINT MONO (-715 3960);
FORCEPROP 0 LASTPIN (-725 4000) $PN 81
J 0
(-715 4010);
DISPLAY 0.680851 (-715 4010);
PAINT MONO (-715 4010);
FORCEPROP 0 LASTPIN (-725 4050) $PN 83
J 0
(-715 4060);
DISPLAY 0.680851 (-715 4060);
PAINT MONO (-715 4060);
FORCEPROP 0 LASTPIN (-725 4100) $PN 85
J 0
(-715 4110);
DISPLAY 0.680851 (-715 4110);
PAINT MONO (-715 4110);
FORCEPROP 0 LASTPIN (-725 4150) $PN 88
J 0
(-715 4160);
DISPLAY 0.680851 (-715 4160);
PAINT MONO (-715 4160);
FORCEPROP 0 LASTPIN (-725 4200) $PN 90
J 0
(-715 4210);
DISPLAY 0.680851 (-715 4210);
PAINT MONO (-715 4210);
FORCEPROP 0 LASTPIN (-725 4250) $PN 92
J 0
(-715 4260);
DISPLAY 0.680851 (-715 4260);
PAINT MONO (-715 4260);
FORCEPROP 0 LASTPIN (-725 4300) $PN 95
J 0
(-715 4310);
DISPLAY 0.680851 (-715 4310);
PAINT MONO (-715 4310);
FORCEPROP 0 LASTPIN (-725 4350) $PN 97
J 0
(-715 4360);
DISPLAY 0.680851 (-715 4360);
PAINT MONO (-715 4360);
FORCEPROP 0 LASTPIN (-725 4400) $PN 99
J 0
(-715 4410);
DISPLAY 0.680851 (-715 4410);
PAINT MONO (-715 4410);
FORCEPROP 0 LASTPIN (-725 4450) $PN 101
J 0
(-715 4460);
DISPLAY 0.680851 (-715 4460);
PAINT MONO (-715 4460);
FORCEPROP 0 LASTPIN (-725 4500) $PN 103
J 0
(-715 4510);
DISPLAY 0.680851 (-715 4510);
PAINT MONO (-715 4510);
FORCEPROP 0 LASTPIN (-725 4550) $PN 106
J 0
(-715 4560);
DISPLAY 0.680851 (-715 4560);
PAINT MONO (-715 4560);
FORCEPROP 0 LASTPIN (-725 4600) $PN 108
J 0
(-715 4610);
DISPLAY 0.680851 (-715 4610);
PAINT MONO (-715 4610);
FORCEPROP 0 LASTPIN (-725 4650) $PN 110
J 0
(-715 4660);
DISPLAY 0.680851 (-715 4660);
PAINT MONO (-715 4660);
FORCEPROP 0 LASTPIN (-725 4700) $PN 112
J 0
(-715 4710);
DISPLAY 0.680851 (-715 4710);
PAINT MONO (-715 4710);
FORCEPROP 0 LASTPIN (-725 4750) $PN 114
J 0
(-715 4760);
DISPLAY 0.680851 (-715 4760);
PAINT MONO (-715 4760);
FORCEPROP 0 LASTPIN (-725 4800) $PN 117
J 0
(-715 4810);
DISPLAY 0.680851 (-715 4810);
PAINT MONO (-715 4810);
FORCEPROP 0 LASTPIN (-725 4850) $PN 119
J 0
(-715 4860);
DISPLAY 0.680851 (-715 4860);
PAINT MONO (-715 4860);
FORCEPROP 0 LASTPIN (-725 4900) $PN 121
J 0
(-715 4910);
DISPLAY 0.680851 (-715 4910);
PAINT MONO (-715 4910);
FORCEPROP 0 LASTPIN (-725 4950) $PN 123
J 0
(-715 4960);
DISPLAY 0.680851 (-715 4960);
PAINT MONO (-715 4960);
FORCEPROP 0 LASTPIN (-725 5000) $PN 125
J 0
(-715 5010);
DISPLAY 0.680851 (-715 5010);
PAINT MONO (-715 5010);
FORCEPROP 0 LASTPIN (-725 5050) $PN 128
J 0
(-715 5060);
DISPLAY 0.680851 (-715 5060);
PAINT MONO (-715 5060);
FORCEPROP 0 LASTPIN (-725 5100) $PN 130
J 0
(-715 5110);
DISPLAY 0.680851 (-715 5110);
PAINT MONO (-715 5110);
FORCEPROP 0 LASTPIN (-725 5150) $PN 132
J 0
(-715 5160);
DISPLAY 0.680851 (-715 5160);
PAINT MONO (-715 5160);
FORCEPROP 0 LASTPIN (-725 5200) $PN 134
J 0
(-715 5210);
DISPLAY 0.680851 (-715 5210);
PAINT MONO (-715 5210);
FORCEPROP 0 LASTPIN (-725 5250) $PN 136
J 0
(-715 5260);
DISPLAY 0.680851 (-715 5260);
PAINT MONO (-715 5260);
FORCEPROP 0 LASTPIN (-725 5300) $PN 139
J 0
(-715 5310);
DISPLAY 0.680851 (-715 5310);
PAINT MONO (-715 5310);
FORCEPROP 0 LASTPIN (-725 5350) $PN 141
J 0
(-715 5360);
DISPLAY 0.680851 (-715 5360);
PAINT MONO (-715 5360);
FORCEPROP 0 LASTPIN (-725 5400) $PN 143
J 0
(-715 5410);
DISPLAY 0.680851 (-715 5410);
PAINT MONO (-715 5410);
FORCEPROP 0 LASTPIN (-1925 2150) $PN 151
J 2
(-1935 2160);
DISPLAY 0.680851 (-1935 2160);
PAINT MONO (-1935 2160);
FORCEPROP 0 LASTPIN (-1925 2200) $PN 153
J 2
(-1935 2210);
DISPLAY 0.680851 (-1935 2210);
PAINT MONO (-1935 2210);
FORCEPROP 0 LASTPIN (-1925 2250) $PN 155
J 2
(-1935 2260);
DISPLAY 0.680851 (-1935 2260);
PAINT MONO (-1935 2260);
FORCEPROP 0 LASTPIN (-1925 2300) $PN 158
J 2
(-1935 2310);
DISPLAY 0.680851 (-1935 2310);
PAINT MONO (-1935 2310);
FORCEPROP 0 LASTPIN (-1925 2350) $PN 160
J 2
(-1935 2360);
DISPLAY 0.680851 (-1935 2360);
PAINT MONO (-1935 2360);
FORCEPROP 0 LASTPIN (-1925 2400) $PN 162
J 2
(-1935 2410);
DISPLAY 0.680851 (-1935 2410);
PAINT MONO (-1935 2410);
FORCEPROP 0 LASTPIN (-1925 2450) $PN 164
J 2
(-1935 2460);
DISPLAY 0.680851 (-1935 2460);
PAINT MONO (-1935 2460);
FORCEPROP 0 LASTPIN (-1925 2500) $PN 166
J 2
(-1935 2510);
DISPLAY 0.680851 (-1935 2510);
PAINT MONO (-1935 2510);
FORCEPROP 0 LASTPIN (-1925 2550) $PN 169
J 2
(-1935 2560);
DISPLAY 0.680851 (-1935 2560);
PAINT MONO (-1935 2560);
FORCEPROP 0 LASTPIN (-1925 2600) $PN 171
J 2
(-1935 2610);
DISPLAY 0.680851 (-1935 2610);
PAINT MONO (-1935 2610);
FORCEPROP 0 LASTPIN (-1925 2650) $PN 173
J 2
(-1935 2660);
DISPLAY 0.680851 (-1935 2660);
PAINT MONO (-1935 2660);
FORCEPROP 0 LASTPIN (-1925 2700) $PN 175
J 2
(-1935 2710);
DISPLAY 0.680851 (-1935 2710);
PAINT MONO (-1935 2710);
FORCEPROP 0 LASTPIN (-1925 2750) $PN 177
J 2
(-1935 2760);
DISPLAY 0.680851 (-1935 2760);
PAINT MONO (-1935 2760);
FORCEPROP 0 LASTPIN (-1925 2800) $PN 180
J 2
(-1935 2810);
DISPLAY 0.680851 (-1935 2810);
PAINT MONO (-1935 2810);
FORCEPROP 0 LASTPIN (-1925 2850) $PN 182
J 2
(-1935 2860);
DISPLAY 0.680851 (-1935 2860);
PAINT MONO (-1935 2860);
FORCEPROP 0 LASTPIN (-1925 2900) $PN 184
J 2
(-1935 2910);
DISPLAY 0.680851 (-1935 2910);
PAINT MONO (-1935 2910);
FORCEPROP 0 LASTPIN (-1925 2950) $PN 186
J 2
(-1935 2960);
DISPLAY 0.680851 (-1935 2960);
PAINT MONO (-1935 2960);
FORCEPROP 0 LASTPIN (-1925 3000) $PN 188
J 2
(-1935 3010);
DISPLAY 0.680851 (-1935 3010);
PAINT MONO (-1935 3010);
FORCEPROP 0 LASTPIN (-1925 3050) $PN 191
J 2
(-1935 3060);
DISPLAY 0.680851 (-1935 3060);
PAINT MONO (-1935 3060);
FORCEPROP 0 LASTPIN (-1925 3100) $PN 193
J 2
(-1935 3110);
DISPLAY 0.680851 (-1935 3110);
PAINT MONO (-1935 3110);
FORCEPROP 0 LASTPIN (-1925 3150) $PN 195
J 2
(-1935 3160);
DISPLAY 0.680851 (-1935 3160);
PAINT MONO (-1935 3160);
FORCEPROP 0 LASTPIN (-1925 3200) $PN 197
J 2
(-1935 3210);
DISPLAY 0.680851 (-1935 3210);
PAINT MONO (-1935 3210);
FORCEPROP 0 LASTPIN (-1925 3250) $PN 199
J 2
(-1935 3260);
DISPLAY 0.680851 (-1935 3260);
PAINT MONO (-1935 3260);
FORCEPROP 0 LASTPIN (-1925 3300) $PN 202
J 2
(-1935 3310);
DISPLAY 0.680851 (-1935 3310);
PAINT MONO (-1935 3310);
FORCEPROP 0 LASTPIN (-1925 3350) $PN 204
J 2
(-1935 3360);
DISPLAY 0.680851 (-1935 3360);
PAINT MONO (-1935 3360);
FORCEPROP 0 LASTPIN (-1925 3400) $PN 206
J 2
(-1935 3410);
DISPLAY 0.680851 (-1935 3410);
PAINT MONO (-1935 3410);
FORCEPROP 0 LASTPIN (-1925 3450) $PN 208
J 2
(-1935 3460);
DISPLAY 0.680851 (-1935 3460);
PAINT MONO (-1935 3460);
FORCEPROP 0 LASTPIN (-1925 3500) $PN 210
J 2
(-1935 3510);
DISPLAY 0.680851 (-1935 3510);
PAINT MONO (-1935 3510);
FORCEPROP 0 LASTPIN (-1925 3550) $PN 212
J 2
(-1935 3560);
DISPLAY 0.680851 (-1935 3560);
PAINT MONO (-1935 3560);
FORCEPROP 0 LASTPIN (-1925 3600) $PN 214
J 2
(-1935 3610);
DISPLAY 0.680851 (-1935 3610);
PAINT MONO (-1935 3610);
FORCEPROP 0 LASTPIN (-1925 3650) $PN 216
J 2
(-1935 3660);
DISPLAY 0.680851 (-1935 3660);
PAINT MONO (-1935 3660);
FORCEPROP 0 LASTPIN (-1925 3700) $PN 219
J 2
(-1935 3710);
DISPLAY 0.680851 (-1935 3710);
PAINT MONO (-1935 3710);
FORCEPROP 0 LASTPIN (-1925 3750) $PN 222
J 2
(-1935 3760);
DISPLAY 0.680851 (-1935 3760);
PAINT MONO (-1935 3760);
FORCEPROP 0 LASTPIN (-1925 3800) $PN 224
J 2
(-1935 3810);
DISPLAY 0.680851 (-1935 3810);
PAINT MONO (-1935 3810);
FORCEPROP 0 LASTPIN (-1925 3850) $PN 226
J 2
(-1935 3860);
DISPLAY 0.680851 (-1935 3860);
PAINT MONO (-1935 3860);
FORCEPROP 0 LASTPIN (-1925 3900) $PN 228
J 2
(-1935 3910);
DISPLAY 0.680851 (-1935 3910);
PAINT MONO (-1935 3910);
FORCEPROP 0 LASTPIN (-1925 3950) $PN 230
J 2
(-1935 3960);
DISPLAY 0.680851 (-1935 3960);
PAINT MONO (-1935 3960);
FORCEPROP 0 LASTPIN (-1925 4000) $PN 233
J 2
(-1935 4010);
DISPLAY 0.680851 (-1935 4010);
PAINT MONO (-1935 4010);
FORCEPROP 0 LASTPIN (-1925 4050) $PN 235
J 2
(-1935 4060);
DISPLAY 0.680851 (-1935 4060);
PAINT MONO (-1935 4060);
FORCEPROP 0 LASTPIN (-1925 4100) $PN 237
J 2
(-1935 4110);
DISPLAY 0.680851 (-1935 4110);
PAINT MONO (-1935 4110);
FORCEPROP 0 LASTPIN (-1925 4150) $PN 240
J 2
(-1935 4160);
DISPLAY 0.680851 (-1935 4160);
PAINT MONO (-1935 4160);
FORCEPROP 0 LASTPIN (-1925 4200) $PN 242
J 2
(-1935 4210);
DISPLAY 0.680851 (-1935 4210);
PAINT MONO (-1935 4210);
FORCEPROP 0 LASTPIN (-1925 4250) $PN 244
J 2
(-1935 4260);
DISPLAY 0.680851 (-1935 4260);
PAINT MONO (-1935 4260);
FORCEPROP 0 LASTPIN (-1925 4300) $PN 246
J 2
(-1935 4310);
DISPLAY 0.680851 (-1935 4310);
PAINT MONO (-1935 4310);
FORCEPROP 0 LASTPIN (-1925 4350) $PN 248
J 2
(-1935 4360);
DISPLAY 0.680851 (-1935 4360);
PAINT MONO (-1935 4360);
FORCEPROP 0 LASTPIN (-1925 4400) $PN 251
J 2
(-1935 4410);
DISPLAY 0.680851 (-1935 4410);
PAINT MONO (-1935 4410);
FORCEPROP 0 LASTPIN (-1925 4450) $PN 253
J 2
(-1935 4460);
DISPLAY 0.680851 (-1935 4460);
PAINT MONO (-1935 4460);
FORCEPROP 0 LASTPIN (-1925 4500) $PN 255
J 2
(-1935 4510);
DISPLAY 0.680851 (-1935 4510);
PAINT MONO (-1935 4510);
FORCEPROP 0 LASTPIN (-1925 4550) $PN 257
J 2
(-1935 4560);
DISPLAY 0.680851 (-1935 4560);
PAINT MONO (-1935 4560);
FORCEPROP 0 LASTPIN (-1925 4600) $PN 259
J 2
(-1935 4610);
DISPLAY 0.680851 (-1935 4610);
PAINT MONO (-1935 4610);
FORCEPROP 0 LASTPIN (-1925 4650) $PN 262
J 2
(-1935 4660);
DISPLAY 0.680851 (-1935 4660);
PAINT MONO (-1935 4660);
FORCEPROP 0 LASTPIN (-1925 4700) $PN 264
J 2
(-1935 4710);
DISPLAY 0.680851 (-1935 4710);
PAINT MONO (-1935 4710);
FORCEPROP 0 LASTPIN (-1925 4750) $PN 266
J 2
(-1935 4760);
DISPLAY 0.680851 (-1935 4760);
PAINT MONO (-1935 4760);
FORCEPROP 0 LASTPIN (-1925 4800) $PN 268
J 2
(-1935 4810);
DISPLAY 0.680851 (-1935 4810);
PAINT MONO (-1935 4810);
FORCEPROP 0 LASTPIN (-1925 4850) $PN 270
J 2
(-1935 4860);
DISPLAY 0.680851 (-1935 4860);
PAINT MONO (-1935 4860);
FORCEPROP 0 LASTPIN (-1925 4900) $PN 273
J 2
(-1935 4910);
DISPLAY 0.680851 (-1935 4910);
PAINT MONO (-1935 4910);
FORCEPROP 0 LASTPIN (-1925 4950) $PN 275
J 2
(-1935 4960);
DISPLAY 0.680851 (-1935 4960);
PAINT MONO (-1935 4960);
FORCEPROP 0 LASTPIN (-1925 5000) $PN 277
J 2
(-1935 5010);
DISPLAY 0.680851 (-1935 5010);
PAINT MONO (-1935 5010);
FORCEPROP 0 LASTPIN (-1925 5050) $PN 279
J 2
(-1935 5060);
DISPLAY 0.680851 (-1935 5060);
PAINT MONO (-1935 5060);
FORCEPROP 0 LASTPIN (-1925 5100) $PN 281
J 2
(-1935 5110);
DISPLAY 0.680851 (-1935 5110);
PAINT MONO (-1935 5110);
FORCEPROP 0 LASTPIN (-1925 5150) $PN 284
J 2
(-1935 5160);
DISPLAY 0.680851 (-1935 5160);
PAINT MONO (-1935 5160);
FORCEPROP 0 LASTPIN (-1925 5200) $PN 286
J 2
(-1935 5210);
DISPLAY 0.680851 (-1935 5210);
PAINT MONO (-1935 5210);
FORCEPROP 0 LASTPIN (-1925 5250) $PN 288
J 2
(-1935 5260);
DISPLAY 0.680851 (-1935 5260);
PAINT MONO (-1935 5260);
FORCEPROP 1 LAST MATERIAL IO
J 0
(-1775 5575);
DISPLAY 0.468085 (-1775 5575);
PAINT SKYBLUE (-1775 5575);
FORCEPROP 2 LAST PART_TYPE SMLF
J 0
(-1775 5825);
DISPLAY 1.021277 (-1775 5825);
FORCEPROP 2 LAST VALUE SCONN288_DDR506112002KQ
J 0
(-1775 5775);
DISPLAY 0.489362 (-1775 5775);
PAINT SKYBLUE (-1775 5775);
FORCEPROP 1 LAST CDS_LMAN_SYM_OUTLINE -450,1800,450,-1750
J 0
(-1325 3750);
DISPLAY 0.468085 (-1325 3750);
PAINT GREEN (-1325 3750);
DISPLAY INVISIBLE (-1325 3750);
FORCEPROP 1 LAST NEEDS_NO_SIZE TRUE
J 0
(-1325 3750);
DISPLAY 0.723404 (-1325 3750);
PAINT GREEN (-1325 3750);
DISPLAY INVISIBLE (-1325 3750);
FORCEPROP 2 LAST CDS_LIB pure_quanta
J 0
(-1325 3750);
DISPLAY INVISIBLE (-1325 3750);
FORCEPROP 1 LAST PATH I155
J 0
(-1325 3750);
DISPLAY 0.723404 (-1325 3750);
PAINT GREEN (-1325 3750);
DISPLAY INVISIBLE (-1325 3750);
FORCEPROP 1 LAST PART_NUMBER DFHST8FS479
J 0
(-1775 5650);
DISPLAY 0.468085 (-1775 5650);
PAINT SKYBLUE (-1775 5650);
DISPLAY INVISIBLE (-1775 5650);
FORCEADD GND..1
(-425 1800);
FORCEPROP 3 LASTPIN (-425 1850) SIG_NAME GND\g
J 0
(-415 1860);
DISPLAY 0.659574 (-415 1860);
PAINT MONO (-415 1860);
DISPLAY INVISIBLE (-415 1860);
FORCEPROP 1 LAST SIZE 1B
J 0
(-350 1750);
DISPLAY 0.851064 (-350 1750);
PAINT GREEN (-350 1750);
DISPLAY INVISIBLE (-350 1750);
FORCEPROP 2 LAST CDS_LIB mstr_symbols
J 0
(-425 1800);
DISPLAY 0.723404 (-425 1800);
DISPLAY INVISIBLE (-425 1800);
FORCEPROP 1 LAST VOLTAGE 0.0
J 0
(-470 1757);
DISPLAY 0.723404 (-470 1757);
PAINT SKYBLUE (-470 1757);
DISPLAY INVISIBLE (-470 1757);
FORCEPROP 1 LAST BODY_TYPE PLUMBING
J 0
(-470 1757);
DISPLAY 0.340426 (-470 1757);
PAINT GREEN (-470 1757);
DISPLAY INVISIBLE (-470 1757);
FORCEPROP 1 LAST HDL_POWER GND
J 0
(-425 1950);
DISPLAY 0.851064 (-425 1950);
PAINT GREEN (-425 1950);
DISPLAY INVISIBLE (-425 1950);
FORCEPROP 1 LAST PATH I156
J 0
(-350 1800);
DISPLAY 0.872340 (-350 1800);
PAINT AQUA (-350 1800);
DISPLAY INVISIBLE (-350 1800);
FORCEADD OFFPAGE..1
(-8500 4550);
FORCEPROP 2 LAST $XR0 39 
J 0
(-8721 4550);
DISPLAY 0.638298 (-8721 4550);
PAINT MONO (-8721 4550);
FORCEPROP 2 LAST CDS_LIB mstr_standard
J 0
(-8500 4550);
DISPLAY 0.808511 (-8500 4550);
DISPLAY INVISIBLE (-8500 4550);
FORCEPROP 1 LAST OFFPAGE TRUE
J 0
(-8175 4425);
DISPLAY 0.872340 (-8175 4425);
PAINT GREEN (-8175 4425);
DISPLAY INVISIBLE (-8175 4425);
FORCEPROP 1 LAST COMMENT_BODY TRUE
J 0
(-8375 4450);
DISPLAY 0.872340 (-8375 4450);
PAINT GREEN (-8375 4450);
DISPLAY INVISIBLE (-8375 4450);
FORCEPROP 2 LAST PATH I16
J 0
(-8700 4600);
DISPLAY 1.021277 (-8700 4600);
DISPLAY INVISIBLE (-8700 4600);
FORCEADD OFFPAGE..1
(-8500 4450);
FORCEPROP 2 LAST $XR0 39 
J 0
(-8721 4450);
DISPLAY 0.638298 (-8721 4450);
PAINT MONO (-8721 4450);
FORCEPROP 2 LAST CDS_LIB mstr_standard
J 0
(-8500 4450);
DISPLAY 0.723404 (-8500 4450);
PAINT MONO (-8500 4450);
DISPLAY INVISIBLE (-8500 4450);
FORCEPROP 1 LAST OFFPAGE TRUE
J 0
(-8175 4325);
DISPLAY 0.872340 (-8175 4325);
PAINT GREEN (-8175 4325);
DISPLAY INVISIBLE (-8175 4325);
FORCEPROP 1 LAST COMMENT_BODY TRUE
J 0
(-8375 4350);
DISPLAY 0.872340 (-8375 4350);
PAINT GREEN (-8375 4350);
DISPLAY INVISIBLE (-8375 4350);
FORCEPROP 2 LAST PATH I17
J 0
(-8700 4500);
DISPLAY 1.021277 (-8700 4500);
DISPLAY INVISIBLE (-8700 4500);
FORCEADD OFFPAGE..1
(-8500 4400);
FORCEPROP 2 LAST $XR0 39 
J 0
(-8721 4400);
DISPLAY 0.638298 (-8721 4400);
PAINT MONO (-8721 4400);
FORCEPROP 2 LAST CDS_LIB mstr_standard
J 0
(-8500 4400);
DISPLAY 0.808511 (-8500 4400);
DISPLAY INVISIBLE (-8500 4400);
FORCEPROP 1 LAST OFFPAGE TRUE
J 0
(-8175 4275);
DISPLAY 0.872340 (-8175 4275);
PAINT GREEN (-8175 4275);
DISPLAY INVISIBLE (-8175 4275);
FORCEPROP 1 LAST COMMENT_BODY TRUE
J 0
(-8375 4300);
DISPLAY 0.872340 (-8375 4300);
PAINT GREEN (-8375 4300);
DISPLAY INVISIBLE (-8375 4300);
FORCEPROP 2 LAST PATH I18
J 0
(-8700 4450);
DISPLAY 1.021277 (-8700 4450);
DISPLAY INVISIBLE (-8700 4450);
FORCEADD Q_CAP..1
R 2
(-8775 3225);
FORCEPROP 1 LAST LOCATION C144
J 2
(-8825 3325);
DISPLAY 0.489362 (-8825 3325);
PAINT SKYBLUE (-8825 3325);
FORCEPROP 0 LAST $SEC 1
J 0
(-8825 3375);
DISPLAY 0.680851 (-8825 3375);
PAINT MONO (-8825 3375);
DISPLAY INVISIBLE (-8825 3375);
FORCEPROP 0 LAST CDS_SEC 1
J 0
(-8825 3375);
DISPLAY 1.021277 (-8825 3375);
DISPLAY INVISIBLE (-8825 3375);
FORCEPROP 1 LASTPIN (-8775 3325) $PN 1
J 2
(-8785 3305);
DISPLAY 0.489362 (-8785 3305);
PAINT MONO (-8785 3305);
FORCEPROP 1 LASTPIN (-8775 3125) $PN 2
J 2
(-8785 3105);
DISPLAY 0.489362 (-8785 3105);
PAINT MONO (-8785 3105);
FORCEPROP 1 LAST MATERIAL X7R
J 2
(-8825 3125);
DISPLAY 0.489362 (-8825 3125);
PAINT SKYBLUE (-8825 3125);
FORCEPROP 1 LAST PACK_TYPE 0402
J 2
(-8825 3025);
DISPLAY 0.489362 (-8825 3025);
PAINT SKYBLUE (-8825 3025);
FORCEPROP 1 LAST TOLERANCE 10%
J 2
(-8825 3175);
DISPLAY 0.489362 (-8825 3175);
PAINT SKYBLUE (-8825 3175);
FORCEPROP 1 LAST VALUE 0.1UF
J 2
(-8825 3275);
DISPLAY 0.489362 (-8825 3275);
PAINT SKYBLUE (-8825 3275);
FORCEPROP 1 LAST VOLTAGE 25V
J 2
(-8825 3225);
DISPLAY 0.489362 (-8825 3225);
PAINT SKYBLUE (-8825 3225);
FORCEPROP 2 LAST CDS_LIB pure_quanta
J 0
(-8775 3225);
DISPLAY INVISIBLE (-8775 3225);
FORCEPROP 0 LAST BOM_COST MEM
J 2
(-8830 3370);
DISPLAY 0.595745 (-8830 3370);
PAINT MONO (-8830 3370);
DISPLAY INVISIBLE (-8830 3370);
FORCEPROP 2 LAST ROOM 
J 2
(-8830 3370);
DISPLAY 0.595745 (-8830 3370);
PAINT RED (-8830 3370);
DISPLAY INVISIBLE (-8830 3370);
FORCEPROP 1 LAST PATH I185
J 2
(-8825 3375);
DISPLAY 0.978723 (-8825 3375);
PAINT WHITE (-8825 3375);
DISPLAY INVISIBLE (-8825 3375);
FORCEPROP 1 LAST PART_NUMBER CH4104K1B00
J 2
(-8825 3075);
DISPLAY 0.489362 (-8825 3075);
PAINT SKYBLUE (-8825 3075);
DISPLAY INVISIBLE (-8825 3075);
FORCEADD GND..1
(-8775 3000);
FORCEPROP 3 LASTPIN (-8775 3050) SIG_NAME GND\g
J 0
(-8765 3060);
DISPLAY 0.659574 (-8765 3060);
PAINT MONO (-8765 3060);
DISPLAY INVISIBLE (-8765 3060);
FORCEPROP 2 LAST BOM_COST MEM
J 0
(-8750 3125);
DISPLAY 0.659574 (-8750 3125);
DISPLAY INVISIBLE (-8750 3125);
FORCEPROP 1 LAST SIZE 1B
J 0
(-8700 2950);
DISPLAY 0.723404 (-8700 2950);
PAINT GREEN (-8700 2950);
DISPLAY INVISIBLE (-8700 2950);
FORCEPROP 2 LAST CDS_LIB mstr_symbols
J 0
(-8775 3000);
DISPLAY 0.808511 (-8775 3000);
DISPLAY INVISIBLE (-8775 3000);
FORCEPROP 1 LAST VOLTAGE 0
J 0
(-8795 3095);
DISPLAY 0.829787 (-8795 3095);
PAINT SKYBLUE (-8795 3095);
DISPLAY INVISIBLE (-8795 3095);
FORCEPROP 2 LAST ROOM MEM_EFGH_DECOUPLING_CAPS
J 0
(-8750 3075);
DISPLAY 0.659574 (-8750 3075);
PAINT RED (-8750 3075);
DISPLAY INVISIBLE (-8750 3075);
FORCEPROP 1 LAST BODY_TYPE PLUMBING
J 0
(-8820 2957);
DISPLAY 0.276596 (-8820 2957);
PAINT GREEN (-8820 2957);
DISPLAY INVISIBLE (-8820 2957);
FORCEPROP 1 LAST HDL_POWER GND
J 0
(-8775 3150);
DISPLAY 0.723404 (-8775 3150);
PAINT GREEN (-8775 3150);
DISPLAY INVISIBLE (-8775 3150);
FORCEPROP 1 LAST PATH I186
J 0
(-8700 3000);
DISPLAY 0.872340 (-8700 3000);
PAINT AQUA (-8700 3000);
DISPLAY INVISIBLE (-8700 3000);
FORCEADD OFFPAGE..6
(-9200 2150);
FORCEPROP 2 LAST $XR4 103 
J 0
(-9449 2258);
DISPLAY 0.638298 (-9449 2258);
PAINT MONO (-9449 2258);
FORCEPROP 2 LAST $XR3 102 
J 0
(-9449 2222);
DISPLAY 0.638298 (-9449 2222);
PAINT MONO (-9449 2222);
FORCEPROP 2 LAST $XR2 101 
J 0
(-9449 2186);
DISPLAY 0.638298 (-9449 2186);
PAINT MONO (-9449 2186);
FORCEPROP 2 LAST $XR1 99 
J 0
(-9539 2150);
DISPLAY 0.638298 (-9539 2150);
PAINT MONO (-9539 2150);
FORCEPROP 2 LAST $XR0 98 
J 0
(-9449 2150);
DISPLAY 0.638298 (-9449 2150);
PAINT MONO (-9449 2150);
FORCEPROP 2 LAST CDS_LIB mstr_standard
J 0
(-9200 2150);
DISPLAY 0.808511 (-9200 2150);
DISPLAY INVISIBLE (-9200 2150);
FORCEPROP 1 LAST OFFPAGE TRUE
J 0
(-8875 2025);
DISPLAY 0.872340 (-8875 2025);
PAINT GREEN (-8875 2025);
DISPLAY INVISIBLE (-8875 2025);
FORCEPROP 1 LAST COMMENT_BODY TRUE
J 0
(-9100 2075);
DISPLAY 0.872340 (-9100 2075);
PAINT GREEN (-9100 2075);
DISPLAY INVISIBLE (-9100 2075);
FORCEPROP 2 LAST PATH I187
J 0
(-9150 2225);
DISPLAY 1.021277 (-9150 2225);
DISPLAY INVISIBLE (-9150 2225);
FORCEADD Q_RES..1
R 2
(-8700 2150);
FORCEPROP 1 LAST LOCATION R305
J 2
(-8675 2175);
DISPLAY 0.489362 (-8675 2175);
PAINT SKYBLUE (-8675 2175);
FORCEPROP 0 LAST $SEC 1
J 0
(-8675 2225);
DISPLAY 0.680851 (-8675 2225);
PAINT MONO (-8675 2225);
DISPLAY INVISIBLE (-8675 2225);
FORCEPROP 0 LAST CDS_SEC 1
J 0
(-8675 2225);
DISPLAY 1.021277 (-8675 2225);
DISPLAY INVISIBLE (-8675 2225);
FORCEPROP 1 LASTPIN (-8600 2150) $PN 1
J 2
(-8612 2162);
DISPLAY 0.489362 (-8612 2162);
PAINT MONO (-8612 2162);
FORCEPROP 1 LASTPIN (-8800 2150) $PN 2
J 2
(-8762 2162);
DISPLAY 0.489362 (-8762 2162);
PAINT MONO (-8762 2162);
FORCEPROP 1 LAST VALUE 1K
J 0
(-8700 2100);
DISPLAY 0.489362 (-8700 2100);
PAINT SKYBLUE (-8700 2100);
FORCEPROP 1 LAST TOLERANCE 1%
J 2
(-8575 2125);
DISPLAY 0.489362 (-8575 2125);
PAINT SKYBLUE (-8575 2125);
DISPLAY INVISIBLE (-8575 2125);
FORCEPROP 2 LAST BOM_COST MEM
J 0
(-8725 2300);
DISPLAY 0.744681 (-8725 2300);
PAINT WHITE (-8725 2300);
DISPLAY INVISIBLE (-8725 2300);
FORCEPROP 2 LAST CDS_LIB pure_quanta
J 0
(-8700 2150);
DISPLAY INVISIBLE (-8700 2150);
FORCEPROP 1 LAST WATTAGE 1/16W
J 0
(-8625 2075);
DISPLAY 0.489362 (-8625 2075);
PAINT SKYBLUE (-8625 2075);
DISPLAY INVISIBLE (-8625 2075);
FORCEPROP 1 LAST MATERIAL CHIP
J 0
(-8875 2125);
DISPLAY 0.489362 (-8875 2125);
PAINT SKYBLUE (-8875 2125);
DISPLAY INVISIBLE (-8875 2125);
FORCEPROP 1 LAST PACK_TYPE 0402LF
J 0
(-8875 2075);
DISPLAY 0.489362 (-8875 2075);
PAINT SKYBLUE (-8875 2075);
DISPLAY INVISIBLE (-8875 2075);
FORCEPROP 2 LAST ROOM 
J 0
(-8725 2250);
DISPLAY 0.744681 (-8725 2250);
PAINT RED (-8725 2250);
DISPLAY INVISIBLE (-8725 2250);
FORCEPROP 1 LAST PATH I188
J 2
(-8650 2300);
DISPLAY 0.978723 (-8650 2300);
PAINT WHITE (-8650 2300);
DISPLAY INVISIBLE (-8650 2300);
FORCEPROP 1 LAST PART_NUMBER CS21002FB06
J 0
(-8800 2200);
DISPLAY 0.489362 (-8800 2200);
PAINT SKYBLUE (-8800 2200);
DISPLAY INVISIBLE (-8800 2200);
FORCEADD VCC_CORE..1
(-8575 2475);
FORCEPROP 3 LASTPIN (-8575 2425) SIG_NAME P3V3\g
J 0
(-8565 2435);
DISPLAY 0.659574 (-8565 2435);
PAINT MONO (-8565 2435);
DISPLAY INVISIBLE (-8565 2435);
FORCEPROP 1 LAST HDL_POWER P3V3
J 1
(-8575 2525);
DISPLAY 0.489362 (-8575 2525);
PAINT GREEN (-8575 2525);
FORCEPROP 2 LAST CDS_LIB mstr_symbols
J 0
(-8575 2475);
DISPLAY INVISIBLE (-8575 2475);
FORCEPROP 0 LAST VOLTAGE 3.3
J 0
(-8850 2625);
DISPLAY 1.021277 (-8850 2625);
PAINT SKYBLUE (-8850 2625);
DISPLAY INVISIBLE (-8850 2625);
FORCEPROP 2 LAST ROOM PVCCINFAON_CPU0_CTRL
J 0
(-8575 2575);
DISPLAY 0.808511 (-8575 2575);
PAINT RED (-8575 2575);
DISPLAY INVISIBLE (-8575 2575);
FORCEPROP 1 LAST PATH I189
J 0
(-8525 2500);
DISPLAY 0.872340 (-8525 2500);
PAINT AQUA (-8525 2500);
DISPLAY INVISIBLE (-8525 2500);
FORCEADD OFFPAGE..1
(-8500 4600);
FORCEPROP 2 LAST $XR0 39 
J 0
(-8721 4600);
DISPLAY 0.638298 (-8721 4600);
PAINT MONO (-8721 4600);
FORCEPROP 2 LAST CDS_LIB mstr_standard
J 0
(-8500 4600);
DISPLAY 0.723404 (-8500 4600);
PAINT MONO (-8500 4600);
DISPLAY INVISIBLE (-8500 4600);
FORCEPROP 1 LAST OFFPAGE TRUE
J 0
(-8175 4475);
DISPLAY 0.872340 (-8175 4475);
PAINT GREEN (-8175 4475);
DISPLAY INVISIBLE (-8175 4475);
FORCEPROP 1 LAST COMMENT_BODY TRUE
J 0
(-8375 4500);
DISPLAY 0.872340 (-8375 4500);
PAINT GREEN (-8375 4500);
DISPLAY INVISIBLE (-8375 4500);
FORCEPROP 2 LAST PATH I19
J 0
(-8700 4650);
DISPLAY 1.021277 (-8700 4650);
DISPLAY INVISIBLE (-8700 4650);
FORCEADD Q_RES..2
(-8575 2300);
FORCEPROP 1 LAST LOCATION R105
J 0
(-8530 2425);
DISPLAY 0.489362 (-8530 2425);
PAINT SKYBLUE (-8530 2425);
FORCEPROP 0 LAST $SEC 1
J 0
(-8525 2475);
DISPLAY 0.680851 (-8525 2475);
PAINT MONO (-8525 2475);
DISPLAY INVISIBLE (-8525 2475);
FORCEPROP 0 LAST CDS_SEC 1
J 0
(-8525 2475);
DISPLAY 1.021277 (-8525 2475);
DISPLAY INVISIBLE (-8525 2475);
FORCEPROP 1 LASTPIN (-8575 2400) $PN 1
J 0
(-8570 2362);
DISPLAY 0.489362 (-8570 2362);
PAINT MONO (-8570 2362);
FORCEPROP 1 LASTPIN (-8575 2200) $PN 2
J 0
(-8570 2210);
DISPLAY 0.489362 (-8570 2210);
PAINT MONO (-8570 2210);
FORCEPROP 1 LAST TOLERANCE 1%
J 0
(-8525 2350);
DISPLAY 0.489362 (-8525 2350);
PAINT SKYBLUE (-8525 2350);
FORCEPROP 1 LAST MATERIAL EMPTY
J 0
(-8525 2300);
DISPLAY 0.489362 (-8525 2300);
PAINT RED (-8525 2300);
FORCEPROP 1 LAST PACK_TYPE 0402LF
J 0
(-8525 2250);
DISPLAY 0.489362 (-8525 2250);
PAINT SKYBLUE (-8525 2250);
FORCEPROP 1 LAST WATTAGE 1/16W
J 0
(-8525 2325);
DISPLAY 0.489362 (-8525 2325);
PAINT SKYBLUE (-8525 2325);
FORCEPROP 1 LAST VALUE 1K
J 0
(-8530 2375);
DISPLAY 0.489362 (-8530 2375);
PAINT SKYBLUE (-8530 2375);
FORCEPROP 2 LAST CDS_LIB pure_quanta
J 2
(-8575 2300);
DISPLAY INVISIBLE (-8575 2300);
FORCEPROP 2 LAST BOM_COST MEM
J 0
(-8525 2475);
DISPLAY 0.808511 (-8525 2475);
DISPLAY INVISIBLE (-8525 2475);
FORCEPROP 2 LAST ROOM 
J 0
(-8525 2525);
DISPLAY 0.808511 (-8525 2525);
PAINT RED (-8525 2525);
DISPLAY INVISIBLE (-8525 2525);
FORCEPROP 1 LAST PATH I190
J 0
(-8525 2475);
DISPLAY 0.978723 (-8525 2475);
PAINT WHITE (-8525 2475);
DISPLAY INVISIBLE (-8525 2475);
FORCEPROP 1 LAST PART_NUMBER CS21002FB06
J 0
(-8525 2275);
DISPLAY 0.489362 (-8525 2275);
PAINT SKYBLUE (-8525 2275);
DISPLAY INVISIBLE (-8525 2275);
FORCEADD TAP..1
(-3550 3750);
FORCEPROP 3 LASTPIN (-3600 3750) SIG_NAME M_C_CPU1_SA_DQS_DP<1>
J 0
(-3590 3760);
DISPLAY 0.659574 (-3590 3760);
PAINT MONO (-3590 3760);
DISPLAY INVISIBLE (-3590 3760);
FORCEPROP 1 LASTPIN (-3600 3750) BN 1
J 0
(-3612 3758);
DISPLAY 0.489362 (-3612 3758);
PAINT GREEN (-3612 3758);
FORCEPROP 2 LAST CDS_LIB mstr_standard
J 0
(-3550 3750);
DISPLAY 0.723404 (-3550 3750);
PAINT MONO (-3550 3750);
DISPLAY INVISIBLE (-3550 3750);
FORCEPROP 1 LAST BODY_TYPE PLUMBING
J 0
(-3550 3800);
DISPLAY 0.872340 (-3550 3800);
PAINT GREEN (-3550 3800);
DISPLAY INVISIBLE (-3550 3800);
FORCEPROP 1 LAST HDL_TAP TRUE
J 0
(-3225 3625);
DISPLAY 0.872340 (-3225 3625);
DISPLAY INVISIBLE (-3225 3625);
FORCEPROP 1 LAST PATH I191
J 0
(-3552 3750);
DISPLAY 0.872340 (-3552 3750);
PAINT GREEN (-3552 3750);
DISPLAY INVISIBLE (-3552 3750);
FORCEADD TAP..1
(-3550 3850);
FORCEPROP 3 LASTPIN (-3600 3850) SIG_NAME M_C_CPU1_SA_DQS_DP<2>
J 0
(-3590 3860);
DISPLAY 0.659574 (-3590 3860);
PAINT MONO (-3590 3860);
DISPLAY INVISIBLE (-3590 3860);
FORCEPROP 1 LASTPIN (-3600 3850) BN 2
J 0
(-3612 3858);
DISPLAY 0.489362 (-3612 3858);
PAINT GREEN (-3612 3858);
FORCEPROP 2 LAST CDS_LIB mstr_standard
J 0
(-3550 3850);
DISPLAY 0.723404 (-3550 3850);
PAINT MONO (-3550 3850);
DISPLAY INVISIBLE (-3550 3850);
FORCEPROP 1 LAST BODY_TYPE PLUMBING
J 0
(-3550 3900);
DISPLAY 0.872340 (-3550 3900);
PAINT GREEN (-3550 3900);
DISPLAY INVISIBLE (-3550 3900);
FORCEPROP 1 LAST HDL_TAP TRUE
J 0
(-3225 3725);
DISPLAY 0.872340 (-3225 3725);
DISPLAY INVISIBLE (-3225 3725);
FORCEPROP 1 LAST PATH I193
J 0
(-3552 3850);
DISPLAY 0.872340 (-3552 3850);
PAINT GREEN (-3552 3850);
DISPLAY INVISIBLE (-3552 3850);
FORCEADD OFFPAGE..2
(-2550 4600);
FORCEPROP 2 LAST $XR0 39 
J 0
(-2361 4600);
DISPLAY 0.638298 (-2361 4600);
PAINT MONO (-2361 4600);
FORCEPROP 2 LAST CDS_LIB mstr_standard
J 0
(-2550 4600);
DISPLAY 0.723404 (-2550 4600);
PAINT MONO (-2550 4600);
DISPLAY INVISIBLE (-2550 4600);
FORCEPROP 1 LAST OFFPAGE TRUE
J 0
(-2225 4475);
DISPLAY 0.723404 (-2225 4475);
PAINT GREEN (-2225 4475);
DISPLAY INVISIBLE (-2225 4475);
FORCEPROP 1 LAST COMMENT_BODY TRUE
J 0
(-2595 4505);
DISPLAY 0.872340 (-2595 4505);
PAINT GREEN (-2595 4505);
DISPLAY INVISIBLE (-2595 4505);
FORCEPROP 2 LAST PATH I194
J 0
(-2350 4650);
DISPLAY 0.680851 (-2350 4650);
DISPLAY INVISIBLE (-2350 4650);
FORCEADD OFFPAGE..2
(-2550 4550);
FORCEPROP 2 LAST $XR0 39 
J 0
(-2361 4550);
DISPLAY 0.638298 (-2361 4550);
PAINT MONO (-2361 4550);
FORCEPROP 2 LAST CDS_LIB mstr_standard
J 0
(-2550 4550);
DISPLAY 0.723404 (-2550 4550);
PAINT MONO (-2550 4550);
DISPLAY INVISIBLE (-2550 4550);
FORCEPROP 1 LAST OFFPAGE TRUE
J 0
(-2225 4425);
DISPLAY 0.723404 (-2225 4425);
PAINT GREEN (-2225 4425);
DISPLAY INVISIBLE (-2225 4425);
FORCEPROP 1 LAST COMMENT_BODY TRUE
J 0
(-2595 4455);
DISPLAY 0.872340 (-2595 4455);
PAINT GREEN (-2595 4455);
DISPLAY INVISIBLE (-2595 4455);
FORCEPROP 2 LAST PATH I195
J 0
(-2350 4600);
DISPLAY 0.680851 (-2350 4600);
DISPLAY INVISIBLE (-2350 4600);
FORCEADD TAP..1
(-3350 4400);
FORCEPROP 3 LASTPIN (-3400 4400) SIG_NAME M_C_CPU1_SA_DQS_DN<8>
J 0
(-3390 4410);
DISPLAY 0.659574 (-3390 4410);
PAINT MONO (-3390 4410);
DISPLAY INVISIBLE (-3390 4410);
FORCEPROP 1 LASTPIN (-3400 4400) BN 8
J 0
(-3412 4408);
DISPLAY 0.489362 (-3412 4408);
PAINT GREEN (-3412 4408);
FORCEPROP 2 LAST CDS_LIB mstr_standard
J 0
(-3350 4400);
DISPLAY 0.723404 (-3350 4400);
PAINT MONO (-3350 4400);
DISPLAY INVISIBLE (-3350 4400);
FORCEPROP 1 LAST BODY_TYPE PLUMBING
J 0
(-3350 4450);
DISPLAY 0.872340 (-3350 4450);
PAINT GREEN (-3350 4450);
DISPLAY INVISIBLE (-3350 4450);
FORCEPROP 1 LAST HDL_TAP TRUE
J 0
(-3025 4275);
DISPLAY 0.872340 (-3025 4275);
DISPLAY INVISIBLE (-3025 4275);
FORCEPROP 1 LAST PATH I196
J 0
(-3352 4400);
DISPLAY 0.872340 (-3352 4400);
PAINT GREEN (-3352 4400);
DISPLAY INVISIBLE (-3352 4400);
FORCEADD TAP..1
(-3350 4500);
FORCEPROP 3 LASTPIN (-3400 4500) SIG_NAME M_C_CPU1_SA_DQS_DN<9>
J 0
(-3390 4510);
DISPLAY 0.659574 (-3390 4510);
PAINT MONO (-3390 4510);
DISPLAY INVISIBLE (-3390 4510);
FORCEPROP 1 LASTPIN (-3400 4500) BN 9
J 0
(-3412 4508);
DISPLAY 0.489362 (-3412 4508);
PAINT GREEN (-3412 4508);
FORCEPROP 2 LAST CDS_LIB mstr_standard
J 0
(-3350 4500);
DISPLAY 0.723404 (-3350 4500);
PAINT MONO (-3350 4500);
DISPLAY INVISIBLE (-3350 4500);
FORCEPROP 1 LAST BODY_TYPE PLUMBING
J 0
(-3350 4550);
DISPLAY 0.872340 (-3350 4550);
PAINT GREEN (-3350 4550);
DISPLAY INVISIBLE (-3350 4550);
FORCEPROP 1 LAST HDL_TAP TRUE
J 0
(-3025 4375);
DISPLAY 0.872340 (-3025 4375);
DISPLAY INVISIBLE (-3025 4375);
FORCEPROP 1 LAST PATH I197
J 0
(-3352 4500);
DISPLAY 0.872340 (-3352 4500);
PAINT GREEN (-3352 4500);
DISPLAY INVISIBLE (-3352 4500);
FORCEADD TAP..1
(-3550 4450);
FORCEPROP 3 LASTPIN (-3600 4450) SIG_NAME M_C_CPU1_SA_DQS_DP<8>
J 0
(-3590 4460);
DISPLAY 0.659574 (-3590 4460);
PAINT MONO (-3590 4460);
DISPLAY INVISIBLE (-3590 4460);
FORCEPROP 1 LASTPIN (-3600 4450) BN 8
J 0
(-3612 4458);
DISPLAY 0.489362 (-3612 4458);
PAINT GREEN (-3612 4458);
FORCEPROP 2 LAST CDS_LIB mstr_standard
J 0
(-3550 4450);
DISPLAY 0.723404 (-3550 4450);
PAINT MONO (-3550 4450);
DISPLAY INVISIBLE (-3550 4450);
FORCEPROP 1 LAST BODY_TYPE PLUMBING
J 0
(-3550 4500);
DISPLAY 0.872340 (-3550 4500);
PAINT GREEN (-3550 4500);
DISPLAY INVISIBLE (-3550 4500);
FORCEPROP 1 LAST HDL_TAP TRUE
J 0
(-3225 4325);
DISPLAY 0.872340 (-3225 4325);
DISPLAY INVISIBLE (-3225 4325);
FORCEPROP 1 LAST PATH I198
J 0
(-3552 4450);
DISPLAY 0.872340 (-3552 4450);
PAINT GREEN (-3552 4450);
DISPLAY INVISIBLE (-3552 4450);
FORCEADD TAP..1
(-3550 4550);
FORCEPROP 3 LASTPIN (-3600 4550) SIG_NAME M_C_CPU1_SA_DQS_DP<9>
J 0
(-3590 4560);
DISPLAY 0.659574 (-3590 4560);
PAINT MONO (-3590 4560);
DISPLAY INVISIBLE (-3590 4560);
FORCEPROP 1 LASTPIN (-3600 4550) BN 9
J 0
(-3612 4558);
DISPLAY 0.489362 (-3612 4558);
PAINT GREEN (-3612 4558);
FORCEPROP 2 LAST CDS_LIB mstr_standard
J 0
(-3550 4550);
DISPLAY 0.723404 (-3550 4550);
PAINT MONO (-3550 4550);
DISPLAY INVISIBLE (-3550 4550);
FORCEPROP 1 LAST BODY_TYPE PLUMBING
J 0
(-3550 4600);
DISPLAY 0.872340 (-3550 4600);
PAINT GREEN (-3550 4600);
DISPLAY INVISIBLE (-3550 4600);
FORCEPROP 1 LAST HDL_TAP TRUE
J 0
(-3225 4425);
DISPLAY 0.872340 (-3225 4425);
DISPLAY INVISIBLE (-3225 4425);
FORCEPROP 1 LAST PATH I199
J 0
(-3552 4550);
DISPLAY 0.872340 (-3552 4550);
PAINT GREEN (-3552 4550);
DISPLAY INVISIBLE (-3552 4550);
FORCEADD OFFPAGE..5
(-8500 1950);
FORCEPROP 2 LAST $XR0 39 
J 0
(-8754 1950);
DISPLAY 0.638298 (-8754 1950);
PAINT MONO (-8754 1950);
FORCEPROP 2 LAST CDS_LIB mstr_standard
J 0
(-8500 1950);
DISPLAY 0.808511 (-8500 1950);
DISPLAY INVISIBLE (-8500 1950);
FORCEPROP 1 LAST OFFPAGE TRUE
J 0
(-8175 1825);
DISPLAY 0.872340 (-8175 1825);
PAINT GREEN (-8175 1825);
DISPLAY INVISIBLE (-8175 1825);
FORCEPROP 1 LAST COMMENT_BODY TRUE
J 0
(-8400 1875);
DISPLAY 0.872340 (-8400 1875);
PAINT GREEN (-8400 1875);
DISPLAY INVISIBLE (-8400 1875);
FORCEPROP 2 LAST PATH I2
J 0
(-8750 2000);
DISPLAY 1.021277 (-8750 2000);
DISPLAY INVISIBLE (-8750 2000);
FORCEADD OFFPAGE..1
(-8500 5050);
FORCEPROP 2 LAST $XR0 39 
J 0
(-8721 5050);
DISPLAY 0.638298 (-8721 5050);
PAINT MONO (-8721 5050);
FORCEPROP 2 LAST CDS_LIB mstr_standard
J 0
(-8500 5050);
DISPLAY 0.723404 (-8500 5050);
PAINT MONO (-8500 5050);
DISPLAY INVISIBLE (-8500 5050);
FORCEPROP 1 LAST OFFPAGE TRUE
J 0
(-8175 4925);
DISPLAY 0.872340 (-8175 4925);
PAINT GREEN (-8175 4925);
DISPLAY INVISIBLE (-8175 4925);
FORCEPROP 1 LAST COMMENT_BODY TRUE
J 0
(-8375 4950);
DISPLAY 0.872340 (-8375 4950);
PAINT GREEN (-8375 4950);
DISPLAY INVISIBLE (-8375 4950);
FORCEPROP 2 LAST PATH I20
J 0
(-8700 5100);
DISPLAY 1.021277 (-8700 5100);
DISPLAY INVISIBLE (-8700 5100);
FORCEADD TAP..1
(-3550 4350);
FORCEPROP 3 LASTPIN (-3600 4350) SIG_NAME M_C_CPU1_SA_DQS_DP<7>
J 0
(-3590 4360);
DISPLAY 0.659574 (-3590 4360);
PAINT MONO (-3590 4360);
DISPLAY INVISIBLE (-3590 4360);
FORCEPROP 1 LASTPIN (-3600 4350) BN 7
J 0
(-3612 4358);
DISPLAY 0.489362 (-3612 4358);
PAINT GREEN (-3612 4358);
FORCEPROP 2 LAST CDS_LIB mstr_standard
J 0
(-3550 4350);
DISPLAY 0.723404 (-3550 4350);
PAINT MONO (-3550 4350);
DISPLAY INVISIBLE (-3550 4350);
FORCEPROP 1 LAST BODY_TYPE PLUMBING
J 0
(-3550 4400);
DISPLAY 0.872340 (-3550 4400);
PAINT GREEN (-3550 4400);
DISPLAY INVISIBLE (-3550 4400);
FORCEPROP 1 LAST HDL_TAP TRUE
J 0
(-3225 4225);
DISPLAY 0.872340 (-3225 4225);
DISPLAY INVISIBLE (-3225 4225);
FORCEPROP 1 LAST PATH I200
J 0
(-3552 4350);
DISPLAY 0.872340 (-3552 4350);
PAINT GREEN (-3552 4350);
DISPLAY INVISIBLE (-3552 4350);
FORCEADD OFFPAGE..2
(-2550 3500);
FORCEPROP 2 LAST $XR0 39 
J 0
(-2361 3500);
DISPLAY 0.638298 (-2361 3500);
PAINT MONO (-2361 3500);
FORCEPROP 2 LAST CDS_LIB mstr_standard
J 0
(-2550 3500);
DISPLAY 0.723404 (-2550 3500);
PAINT MONO (-2550 3500);
DISPLAY INVISIBLE (-2550 3500);
FORCEPROP 1 LAST OFFPAGE TRUE
J 0
(-2225 3375);
DISPLAY 0.723404 (-2225 3375);
PAINT GREEN (-2225 3375);
DISPLAY INVISIBLE (-2225 3375);
FORCEPROP 1 LAST COMMENT_BODY TRUE
J 0
(-2595 3405);
DISPLAY 0.872340 (-2595 3405);
PAINT GREEN (-2595 3405);
DISPLAY INVISIBLE (-2595 3405);
FORCEPROP 2 LAST PATH I201
J 0
(-2350 3550);
DISPLAY 0.680851 (-2350 3550);
DISPLAY INVISIBLE (-2350 3550);
FORCEADD OFFPAGE..2
(-2550 3550);
FORCEPROP 2 LAST $XR0 39 
J 0
(-2361 3550);
DISPLAY 0.638298 (-2361 3550);
PAINT MONO (-2361 3550);
FORCEPROP 2 LAST CDS_LIB mstr_standard
J 0
(-2550 3550);
DISPLAY 0.723404 (-2550 3550);
PAINT MONO (-2550 3550);
DISPLAY INVISIBLE (-2550 3550);
FORCEPROP 1 LAST OFFPAGE TRUE
J 0
(-2225 3425);
DISPLAY 0.723404 (-2225 3425);
PAINT GREEN (-2225 3425);
DISPLAY INVISIBLE (-2225 3425);
FORCEPROP 1 LAST COMMENT_BODY TRUE
J 0
(-2595 3455);
DISPLAY 0.872340 (-2595 3455);
PAINT GREEN (-2595 3455);
DISPLAY INVISIBLE (-2595 3455);
FORCEPROP 2 LAST PATH I202
J 0
(-2350 3600);
DISPLAY 0.680851 (-2350 3600);
DISPLAY INVISIBLE (-2350 3600);
FORCEADD TAP..1
(-3350 4100);
FORCEPROP 3 LASTPIN (-3400 4100) SIG_NAME M_C_CPU1_SA_DQS_DN<5>
J 0
(-3390 4110);
DISPLAY 0.659574 (-3390 4110);
PAINT MONO (-3390 4110);
DISPLAY INVISIBLE (-3390 4110);
FORCEPROP 1 LASTPIN (-3400 4100) BN 5
J 0
(-3412 4108);
DISPLAY 0.489362 (-3412 4108);
PAINT GREEN (-3412 4108);
FORCEPROP 2 LAST CDS_LIB mstr_standard
J 0
(-3350 4100);
DISPLAY 0.723404 (-3350 4100);
PAINT MONO (-3350 4100);
DISPLAY INVISIBLE (-3350 4100);
FORCEPROP 1 LAST BODY_TYPE PLUMBING
J 0
(-3350 4150);
DISPLAY 0.872340 (-3350 4150);
PAINT GREEN (-3350 4150);
DISPLAY INVISIBLE (-3350 4150);
FORCEPROP 1 LAST HDL_TAP TRUE
J 0
(-3025 3975);
DISPLAY 0.872340 (-3025 3975);
DISPLAY INVISIBLE (-3025 3975);
FORCEPROP 1 LAST PATH I203
J 0
(-3352 4100);
DISPLAY 0.872340 (-3352 4100);
PAINT GREEN (-3352 4100);
DISPLAY INVISIBLE (-3352 4100);
FORCEADD TAP..1
(-3350 4300);
FORCEPROP 3 LASTPIN (-3400 4300) SIG_NAME M_C_CPU1_SA_DQS_DN<7>
J 0
(-3390 4310);
DISPLAY 0.659574 (-3390 4310);
PAINT MONO (-3390 4310);
DISPLAY INVISIBLE (-3390 4310);
FORCEPROP 1 LASTPIN (-3400 4300) BN 7
J 0
(-3412 4308);
DISPLAY 0.489362 (-3412 4308);
PAINT GREEN (-3412 4308);
FORCEPROP 2 LAST CDS_LIB mstr_standard
J 0
(-3350 4300);
DISPLAY 0.723404 (-3350 4300);
PAINT MONO (-3350 4300);
DISPLAY INVISIBLE (-3350 4300);
FORCEPROP 1 LAST BODY_TYPE PLUMBING
J 0
(-3350 4350);
DISPLAY 0.872340 (-3350 4350);
PAINT GREEN (-3350 4350);
DISPLAY INVISIBLE (-3350 4350);
FORCEPROP 1 LAST HDL_TAP TRUE
J 0
(-3025 4175);
DISPLAY 0.872340 (-3025 4175);
DISPLAY INVISIBLE (-3025 4175);
FORCEPROP 1 LAST PATH I204
J 0
(-3352 4300);
DISPLAY 0.872340 (-3352 4300);
PAINT GREEN (-3352 4300);
DISPLAY INVISIBLE (-3352 4300);
FORCEADD TAP..1
(-3350 4200);
FORCEPROP 3 LASTPIN (-3400 4200) SIG_NAME M_C_CPU1_SA_DQS_DN<6>
J 0
(-3390 4210);
DISPLAY 0.659574 (-3390 4210);
PAINT MONO (-3390 4210);
DISPLAY INVISIBLE (-3390 4210);
FORCEPROP 1 LASTPIN (-3400 4200) BN 6
J 0
(-3412 4208);
DISPLAY 0.489362 (-3412 4208);
PAINT GREEN (-3412 4208);
FORCEPROP 2 LAST CDS_LIB mstr_standard
J 0
(-3350 4200);
DISPLAY 0.723404 (-3350 4200);
PAINT MONO (-3350 4200);
DISPLAY INVISIBLE (-3350 4200);
FORCEPROP 1 LAST BODY_TYPE PLUMBING
J 0
(-3350 4250);
DISPLAY 0.872340 (-3350 4250);
PAINT GREEN (-3350 4250);
DISPLAY INVISIBLE (-3350 4250);
FORCEPROP 1 LAST HDL_TAP TRUE
J 0
(-3025 4075);
DISPLAY 0.872340 (-3025 4075);
DISPLAY INVISIBLE (-3025 4075);
FORCEPROP 1 LAST PATH I205
J 0
(-3352 4200);
DISPLAY 0.872340 (-3352 4200);
PAINT GREEN (-3352 4200);
DISPLAY INVISIBLE (-3352 4200);
FORCEADD TAP..1
(-3550 4250);
FORCEPROP 3 LASTPIN (-3600 4250) SIG_NAME M_C_CPU1_SA_DQS_DP<6>
J 0
(-3590 4260);
DISPLAY 0.659574 (-3590 4260);
PAINT MONO (-3590 4260);
DISPLAY INVISIBLE (-3590 4260);
FORCEPROP 1 LASTPIN (-3600 4250) BN 6
J 0
(-3612 4258);
DISPLAY 0.489362 (-3612 4258);
PAINT GREEN (-3612 4258);
FORCEPROP 2 LAST CDS_LIB mstr_standard
J 0
(-3550 4250);
DISPLAY 0.723404 (-3550 4250);
PAINT MONO (-3550 4250);
DISPLAY INVISIBLE (-3550 4250);
FORCEPROP 1 LAST BODY_TYPE PLUMBING
J 0
(-3550 4300);
DISPLAY 0.872340 (-3550 4300);
PAINT GREEN (-3550 4300);
DISPLAY INVISIBLE (-3550 4300);
FORCEPROP 1 LAST HDL_TAP TRUE
J 0
(-3225 4125);
DISPLAY 0.872340 (-3225 4125);
DISPLAY INVISIBLE (-3225 4125);
FORCEPROP 1 LAST PATH I206
J 0
(-3552 4250);
DISPLAY 0.872340 (-3552 4250);
PAINT GREEN (-3552 4250);
DISPLAY INVISIBLE (-3552 4250);
FORCEADD TAP..1
(-3550 4150);
FORCEPROP 3 LASTPIN (-3600 4150) SIG_NAME M_C_CPU1_SA_DQS_DP<5>
J 0
(-3590 4160);
DISPLAY 0.659574 (-3590 4160);
PAINT MONO (-3590 4160);
DISPLAY INVISIBLE (-3590 4160);
FORCEPROP 1 LASTPIN (-3600 4150) BN 5
J 0
(-3612 4158);
DISPLAY 0.489362 (-3612 4158);
PAINT GREEN (-3612 4158);
FORCEPROP 2 LAST CDS_LIB mstr_standard
J 0
(-3550 4150);
DISPLAY 0.723404 (-3550 4150);
PAINT MONO (-3550 4150);
DISPLAY INVISIBLE (-3550 4150);
FORCEPROP 1 LAST BODY_TYPE PLUMBING
J 0
(-3550 4200);
DISPLAY 0.872340 (-3550 4200);
PAINT GREEN (-3550 4200);
DISPLAY INVISIBLE (-3550 4200);
FORCEPROP 1 LAST HDL_TAP TRUE
J 0
(-3225 4025);
DISPLAY 0.872340 (-3225 4025);
DISPLAY INVISIBLE (-3225 4025);
FORCEPROP 1 LAST PATH I207
J 0
(-3552 4150);
DISPLAY 0.872340 (-3552 4150);
PAINT GREEN (-3552 4150);
DISPLAY INVISIBLE (-3552 4150);
FORCEADD TAP..1
(-3350 3900);
FORCEPROP 3 LASTPIN (-3400 3900) SIG_NAME M_C_CPU1_SA_DQS_DN<3>
J 0
(-3390 3910);
DISPLAY 0.659574 (-3390 3910);
PAINT MONO (-3390 3910);
DISPLAY INVISIBLE (-3390 3910);
FORCEPROP 1 LASTPIN (-3400 3900) BN 3
J 0
(-3412 3908);
DISPLAY 0.489362 (-3412 3908);
PAINT GREEN (-3412 3908);
FORCEPROP 2 LAST CDS_LIB mstr_standard
J 0
(-3350 3900);
DISPLAY 0.723404 (-3350 3900);
PAINT MONO (-3350 3900);
DISPLAY INVISIBLE (-3350 3900);
FORCEPROP 1 LAST BODY_TYPE PLUMBING
J 0
(-3350 3950);
DISPLAY 0.872340 (-3350 3950);
PAINT GREEN (-3350 3950);
DISPLAY INVISIBLE (-3350 3950);
FORCEPROP 1 LAST HDL_TAP TRUE
J 0
(-3025 3775);
DISPLAY 0.872340 (-3025 3775);
DISPLAY INVISIBLE (-3025 3775);
FORCEPROP 1 LAST PATH I208
J 0
(-3352 3900);
DISPLAY 0.872340 (-3352 3900);
PAINT GREEN (-3352 3900);
DISPLAY INVISIBLE (-3352 3900);
FORCEADD TAP..1
(-3350 4000);
FORCEPROP 3 LASTPIN (-3400 4000) SIG_NAME M_C_CPU1_SA_DQS_DN<4>
J 0
(-3390 4010);
DISPLAY 0.659574 (-3390 4010);
PAINT MONO (-3390 4010);
DISPLAY INVISIBLE (-3390 4010);
FORCEPROP 1 LASTPIN (-3400 4000) BN 4
J 0
(-3412 4008);
DISPLAY 0.489362 (-3412 4008);
PAINT GREEN (-3412 4008);
FORCEPROP 2 LAST CDS_LIB mstr_standard
J 0
(-3350 4000);
DISPLAY 0.723404 (-3350 4000);
PAINT MONO (-3350 4000);
DISPLAY INVISIBLE (-3350 4000);
FORCEPROP 1 LAST BODY_TYPE PLUMBING
J 0
(-3350 4050);
DISPLAY 0.872340 (-3350 4050);
PAINT GREEN (-3350 4050);
DISPLAY INVISIBLE (-3350 4050);
FORCEPROP 1 LAST HDL_TAP TRUE
J 0
(-3025 3875);
DISPLAY 0.872340 (-3025 3875);
DISPLAY INVISIBLE (-3025 3875);
FORCEPROP 1 LAST PATH I209
J 0
(-3352 4000);
DISPLAY 0.872340 (-3352 4000);
PAINT GREEN (-3352 4000);
DISPLAY INVISIBLE (-3352 4000);
FORCEADD OFFPAGE..1
(-8500 5450);
FORCEPROP 2 LAST $XR0 39 
J 0
(-8721 5450);
DISPLAY 0.638298 (-8721 5450);
PAINT MONO (-8721 5450);
FORCEPROP 2 LAST CDS_LIB mstr_standard
J 0
(-8500 5450);
DISPLAY 0.723404 (-8500 5450);
PAINT MONO (-8500 5450);
DISPLAY INVISIBLE (-8500 5450);
FORCEPROP 1 LAST OFFPAGE TRUE
J 0
(-8175 5325);
DISPLAY 0.872340 (-8175 5325);
PAINT GREEN (-8175 5325);
DISPLAY INVISIBLE (-8175 5325);
FORCEPROP 1 LAST COMMENT_BODY TRUE
J 0
(-8375 5350);
DISPLAY 0.872340 (-8375 5350);
PAINT GREEN (-8375 5350);
DISPLAY INVISIBLE (-8375 5350);
FORCEPROP 2 LAST PATH I21
J 0
(-8700 5500);
DISPLAY 1.021277 (-8700 5500);
DISPLAY INVISIBLE (-8700 5500);
FORCEADD TAP..1
(-3550 4050);
FORCEPROP 3 LASTPIN (-3600 4050) SIG_NAME M_C_CPU1_SA_DQS_DP<4>
J 0
(-3590 4060);
DISPLAY 0.659574 (-3590 4060);
PAINT MONO (-3590 4060);
DISPLAY INVISIBLE (-3590 4060);
FORCEPROP 1 LASTPIN (-3600 4050) BN 4
J 0
(-3612 4058);
DISPLAY 0.489362 (-3612 4058);
PAINT GREEN (-3612 4058);
FORCEPROP 2 LAST CDS_LIB mstr_standard
J 0
(-3550 4050);
DISPLAY 0.723404 (-3550 4050);
PAINT MONO (-3550 4050);
DISPLAY INVISIBLE (-3550 4050);
FORCEPROP 1 LAST BODY_TYPE PLUMBING
J 0
(-3550 4100);
DISPLAY 0.872340 (-3550 4100);
PAINT GREEN (-3550 4100);
DISPLAY INVISIBLE (-3550 4100);
FORCEPROP 1 LAST HDL_TAP TRUE
J 0
(-3225 3925);
DISPLAY 0.872340 (-3225 3925);
DISPLAY INVISIBLE (-3225 3925);
FORCEPROP 1 LAST PATH I210
J 0
(-3552 4050);
DISPLAY 0.872340 (-3552 4050);
PAINT GREEN (-3552 4050);
DISPLAY INVISIBLE (-3552 4050);
FORCEADD TAP..1
(-3550 3950);
FORCEPROP 3 LASTPIN (-3600 3950) SIG_NAME M_C_CPU1_SA_DQS_DP<3>
J 0
(-3590 3960);
DISPLAY 0.659574 (-3590 3960);
PAINT MONO (-3590 3960);
DISPLAY INVISIBLE (-3590 3960);
FORCEPROP 1 LASTPIN (-3600 3950) BN 3
J 0
(-3612 3958);
DISPLAY 0.489362 (-3612 3958);
PAINT GREEN (-3612 3958);
FORCEPROP 2 LAST CDS_LIB mstr_standard
J 0
(-3550 3950);
DISPLAY 0.723404 (-3550 3950);
PAINT MONO (-3550 3950);
DISPLAY INVISIBLE (-3550 3950);
FORCEPROP 1 LAST BODY_TYPE PLUMBING
J 0
(-3550 4000);
DISPLAY 0.872340 (-3550 4000);
PAINT GREEN (-3550 4000);
DISPLAY INVISIBLE (-3550 4000);
FORCEPROP 1 LAST HDL_TAP TRUE
J 0
(-3225 3825);
DISPLAY 0.872340 (-3225 3825);
DISPLAY INVISIBLE (-3225 3825);
FORCEPROP 1 LAST PATH I211
J 0
(-3552 3950);
DISPLAY 0.872340 (-3552 3950);
PAINT GREEN (-3552 3950);
DISPLAY INVISIBLE (-3552 3950);
FORCEADD TAP..1
(-3350 3600);
FORCEPROP 3 LASTPIN (-3400 3600) SIG_NAME M_C_CPU1_SA_DQS_DN<0>
J 0
(-3390 3610);
DISPLAY 0.659574 (-3390 3610);
PAINT MONO (-3390 3610);
DISPLAY INVISIBLE (-3390 3610);
FORCEPROP 1 LASTPIN (-3400 3600) BN 0
J 0
(-3412 3608);
DISPLAY 0.489362 (-3412 3608);
PAINT GREEN (-3412 3608);
FORCEPROP 2 LAST CDS_LIB mstr_standard
J 0
(-3350 3600);
DISPLAY 0.723404 (-3350 3600);
PAINT MONO (-3350 3600);
DISPLAY INVISIBLE (-3350 3600);
FORCEPROP 1 LAST BODY_TYPE PLUMBING
J 0
(-3350 3650);
DISPLAY 0.872340 (-3350 3650);
PAINT GREEN (-3350 3650);
DISPLAY INVISIBLE (-3350 3650);
FORCEPROP 1 LAST HDL_TAP TRUE
J 0
(-3025 3475);
DISPLAY 0.872340 (-3025 3475);
DISPLAY INVISIBLE (-3025 3475);
FORCEPROP 1 LAST PATH I212
J 0
(-3352 3600);
DISPLAY 0.872340 (-3352 3600);
PAINT GREEN (-3352 3600);
DISPLAY INVISIBLE (-3352 3600);
FORCEADD TAP..1
(-3350 3800);
FORCEPROP 3 LASTPIN (-3400 3800) SIG_NAME M_C_CPU1_SA_DQS_DN<2>
J 0
(-3390 3810);
DISPLAY 0.659574 (-3390 3810);
PAINT MONO (-3390 3810);
DISPLAY INVISIBLE (-3390 3810);
FORCEPROP 1 LASTPIN (-3400 3800) BN 2
J 0
(-3412 3808);
DISPLAY 0.489362 (-3412 3808);
PAINT GREEN (-3412 3808);
FORCEPROP 2 LAST CDS_LIB mstr_standard
J 0
(-3350 3800);
DISPLAY 0.723404 (-3350 3800);
PAINT MONO (-3350 3800);
DISPLAY INVISIBLE (-3350 3800);
FORCEPROP 1 LAST BODY_TYPE PLUMBING
J 0
(-3350 3850);
DISPLAY 0.872340 (-3350 3850);
PAINT GREEN (-3350 3850);
DISPLAY INVISIBLE (-3350 3850);
FORCEPROP 1 LAST HDL_TAP TRUE
J 0
(-3025 3675);
DISPLAY 0.872340 (-3025 3675);
DISPLAY INVISIBLE (-3025 3675);
FORCEPROP 1 LAST PATH I213
J 0
(-3352 3800);
DISPLAY 0.872340 (-3352 3800);
PAINT GREEN (-3352 3800);
DISPLAY INVISIBLE (-3352 3800);
FORCEADD TAP..1
(-3350 3700);
FORCEPROP 3 LASTPIN (-3400 3700) SIG_NAME M_C_CPU1_SA_DQS_DN<1>
J 0
(-3390 3710);
DISPLAY 0.659574 (-3390 3710);
PAINT MONO (-3390 3710);
DISPLAY INVISIBLE (-3390 3710);
FORCEPROP 1 LASTPIN (-3400 3700) BN 1
J 0
(-3412 3708);
DISPLAY 0.489362 (-3412 3708);
PAINT GREEN (-3412 3708);
FORCEPROP 2 LAST CDS_LIB mstr_standard
J 0
(-3350 3700);
DISPLAY 0.723404 (-3350 3700);
PAINT MONO (-3350 3700);
DISPLAY INVISIBLE (-3350 3700);
FORCEPROP 1 LAST BODY_TYPE PLUMBING
J 0
(-3350 3750);
DISPLAY 0.872340 (-3350 3750);
PAINT GREEN (-3350 3750);
DISPLAY INVISIBLE (-3350 3750);
FORCEPROP 1 LAST HDL_TAP TRUE
J 0
(-3025 3575);
DISPLAY 0.872340 (-3025 3575);
DISPLAY INVISIBLE (-3025 3575);
FORCEPROP 1 LAST PATH I214
J 0
(-3352 3700);
DISPLAY 0.872340 (-3352 3700);
PAINT GREEN (-3352 3700);
DISPLAY INVISIBLE (-3352 3700);
FORCEADD TAP..1
(-3550 3650);
FORCEPROP 3 LASTPIN (-3600 3650) SIG_NAME M_C_CPU1_SA_DQS_DP<0>
J 0
(-3590 3660);
DISPLAY 0.659574 (-3590 3660);
PAINT MONO (-3590 3660);
DISPLAY INVISIBLE (-3590 3660);
FORCEPROP 1 LASTPIN (-3600 3650) BN 0
J 0
(-3612 3658);
DISPLAY 0.489362 (-3612 3658);
PAINT GREEN (-3612 3658);
FORCEPROP 2 LAST CDS_LIB mstr_standard
J 0
(-3550 3650);
DISPLAY 0.723404 (-3550 3650);
PAINT MONO (-3550 3650);
DISPLAY INVISIBLE (-3550 3650);
FORCEPROP 1 LAST BODY_TYPE PLUMBING
J 0
(-3550 3700);
DISPLAY 0.872340 (-3550 3700);
PAINT GREEN (-3550 3700);
DISPLAY INVISIBLE (-3550 3700);
FORCEPROP 1 LAST HDL_TAP TRUE
J 0
(-3225 3525);
DISPLAY 0.872340 (-3225 3525);
DISPLAY INVISIBLE (-3225 3525);
FORCEPROP 1 LAST PATH I215
J 0
(-3552 3650);
DISPLAY 0.872340 (-3552 3650);
PAINT GREEN (-3552 3650);
DISPLAY INVISIBLE (-3552 3650);
FORCEADD TAP..1
(-3350 3350);
FORCEPROP 3 LASTPIN (-3400 3350) SIG_NAME M_C_CPU1_SB_DQS_DN<8>
J 0
(-3390 3360);
DISPLAY 0.659574 (-3390 3360);
PAINT MONO (-3390 3360);
DISPLAY INVISIBLE (-3390 3360);
FORCEPROP 1 LASTPIN (-3400 3350) BN 8
J 0
(-3412 3358);
DISPLAY 0.489362 (-3412 3358);
PAINT GREEN (-3412 3358);
FORCEPROP 2 LAST CDS_LIB mstr_standard
J 0
(-3350 3350);
DISPLAY 0.723404 (-3350 3350);
PAINT MONO (-3350 3350);
DISPLAY INVISIBLE (-3350 3350);
FORCEPROP 1 LAST BODY_TYPE PLUMBING
J 0
(-3350 3400);
DISPLAY 0.872340 (-3350 3400);
PAINT GREEN (-3350 3400);
DISPLAY INVISIBLE (-3350 3400);
FORCEPROP 1 LAST HDL_TAP TRUE
J 0
(-3025 3225);
DISPLAY 0.872340 (-3025 3225);
DISPLAY INVISIBLE (-3025 3225);
FORCEPROP 1 LAST PATH I216
J 0
(-3352 3350);
DISPLAY 0.872340 (-3352 3350);
PAINT GREEN (-3352 3350);
DISPLAY INVISIBLE (-3352 3350);
FORCEADD TAP..1
(-3350 3450);
FORCEPROP 3 LASTPIN (-3400 3450) SIG_NAME M_C_CPU1_SB_DQS_DN<9>
J 0
(-3390 3460);
DISPLAY 0.659574 (-3390 3460);
PAINT MONO (-3390 3460);
DISPLAY INVISIBLE (-3390 3460);
FORCEPROP 1 LASTPIN (-3400 3450) BN 9
J 0
(-3412 3458);
DISPLAY 0.489362 (-3412 3458);
PAINT GREEN (-3412 3458);
FORCEPROP 2 LAST CDS_LIB mstr_standard
J 0
(-3350 3450);
DISPLAY 0.723404 (-3350 3450);
PAINT MONO (-3350 3450);
DISPLAY INVISIBLE (-3350 3450);
FORCEPROP 1 LAST BODY_TYPE PLUMBING
J 0
(-3350 3500);
DISPLAY 0.872340 (-3350 3500);
PAINT GREEN (-3350 3500);
DISPLAY INVISIBLE (-3350 3500);
FORCEPROP 1 LAST HDL_TAP TRUE
J 0
(-3025 3325);
DISPLAY 0.872340 (-3025 3325);
DISPLAY INVISIBLE (-3025 3325);
FORCEPROP 1 LAST PATH I217
J 0
(-3352 3450);
DISPLAY 0.872340 (-3352 3450);
PAINT GREEN (-3352 3450);
DISPLAY INVISIBLE (-3352 3450);
FORCEADD TAP..1
(-3550 3500);
FORCEPROP 3 LASTPIN (-3600 3500) SIG_NAME M_C_CPU1_SB_DQS_DP<9>
J 0
(-3590 3510);
DISPLAY 0.659574 (-3590 3510);
PAINT MONO (-3590 3510);
DISPLAY INVISIBLE (-3590 3510);
FORCEPROP 1 LASTPIN (-3600 3500) BN 9
J 0
(-3612 3508);
DISPLAY 0.489362 (-3612 3508);
PAINT GREEN (-3612 3508);
FORCEPROP 2 LAST CDS_LIB mstr_standard
J 0
(-3550 3500);
DISPLAY 0.723404 (-3550 3500);
PAINT MONO (-3550 3500);
DISPLAY INVISIBLE (-3550 3500);
FORCEPROP 1 LAST BODY_TYPE PLUMBING
J 0
(-3550 3550);
DISPLAY 0.872340 (-3550 3550);
PAINT GREEN (-3550 3550);
DISPLAY INVISIBLE (-3550 3550);
FORCEPROP 1 LAST HDL_TAP TRUE
J 0
(-3225 3375);
DISPLAY 0.872340 (-3225 3375);
DISPLAY INVISIBLE (-3225 3375);
FORCEPROP 1 LAST PATH I218
J 0
(-3552 3500);
DISPLAY 0.872340 (-3552 3500);
PAINT GREEN (-3552 3500);
DISPLAY INVISIBLE (-3552 3500);
FORCEADD TAP..1
(-3550 3400);
FORCEPROP 3 LASTPIN (-3600 3400) SIG_NAME M_C_CPU1_SB_DQS_DP<8>
J 0
(-3590 3410);
DISPLAY 0.659574 (-3590 3410);
PAINT MONO (-3590 3410);
DISPLAY INVISIBLE (-3590 3410);
FORCEPROP 1 LASTPIN (-3600 3400) BN 8
J 0
(-3612 3408);
DISPLAY 0.489362 (-3612 3408);
PAINT GREEN (-3612 3408);
FORCEPROP 2 LAST CDS_LIB mstr_standard
J 0
(-3550 3400);
DISPLAY 0.723404 (-3550 3400);
PAINT MONO (-3550 3400);
DISPLAY INVISIBLE (-3550 3400);
FORCEPROP 1 LAST BODY_TYPE PLUMBING
J 0
(-3550 3450);
DISPLAY 0.872340 (-3550 3450);
PAINT GREEN (-3550 3450);
DISPLAY INVISIBLE (-3550 3450);
FORCEPROP 1 LAST HDL_TAP TRUE
J 0
(-3225 3275);
DISPLAY 0.872340 (-3225 3275);
DISPLAY INVISIBLE (-3225 3275);
FORCEPROP 1 LAST PATH I219
J 0
(-3552 3400);
DISPLAY 0.872340 (-3552 3400);
PAINT GREEN (-3552 3400);
DISPLAY INVISIBLE (-3552 3400);
FORCEADD SCONN288_DDR506112002KQ..1
(-7050 3650);
FORCEPROP 1 LAST LOCATION J28
J 0
(-7500 5725);
DISPLAY 0.468085 (-7500 5725);
PAINT SKYBLUE (-7500 5725);
FORCEPROP 0 LAST $SEC 1
J 0
(-7500 5875);
DISPLAY 0.680851 (-7500 5875);
PAINT MONO (-7500 5875);
DISPLAY INVISIBLE (-7500 5875);
FORCEPROP 2 LAST CDS_SEC 1
J 0
(-7500 5875);
DISPLAY 1.021277 (-7500 5875);
DISPLAY INVISIBLE (-7500 5875);
FORCEPROP 0 LASTPIN (-7650 3050) $PN 62
J 2
(-7660 3060);
DISPLAY 0.680851 (-7660 3060);
PAINT MONO (-7660 3060);
FORCEPROP 0 LASTPIN (-7650 5100) $PN 66
J 2
(-7660 5110);
DISPLAY 0.680851 (-7660 5110);
PAINT MONO (-7660 5110);
FORCEPROP 0 LASTPIN (-7650 4700) $PN 76
J 2
(-7660 4710);
DISPLAY 0.680851 (-7660 4710);
PAINT MONO (-7660 4710);
FORCEPROP 0 LASTPIN (-7650 5150) $PN 211
J 2
(-7660 5160);
DISPLAY 0.680851 (-7660 5160);
PAINT MONO (-7660 5160);
FORCEPROP 0 LASTPIN (-7650 4750) $PN 221
J 2
(-7660 4760);
DISPLAY 0.680851 (-7660 4760);
PAINT MONO (-7660 4760);
FORCEPROP 0 LASTPIN (-7650 5200) $PN 68
J 2
(-7660 5210);
DISPLAY 0.680851 (-7660 5210);
PAINT MONO (-7660 5210);
FORCEPROP 0 LASTPIN (-7650 4800) $PN 78
J 2
(-7660 4810);
DISPLAY 0.680851 (-7660 4810);
PAINT MONO (-7660 4810);
FORCEPROP 0 LASTPIN (-7650 5250) $PN 213
J 2
(-7660 5260);
DISPLAY 0.680851 (-7660 5260);
PAINT MONO (-7660 5260);
FORCEPROP 0 LASTPIN (-7650 4850) $PN 223
J 2
(-7660 4860);
DISPLAY 0.680851 (-7660 4860);
PAINT MONO (-7660 4860);
FORCEPROP 0 LASTPIN (-7650 5300) $PN 70
J 2
(-7660 5310);
DISPLAY 0.680851 (-7660 5310);
PAINT MONO (-7660 5310);
FORCEPROP 0 LASTPIN (-7650 4900) $PN 80
J 2
(-7660 4910);
DISPLAY 0.680851 (-7660 4910);
PAINT MONO (-7660 4910);
FORCEPROP 0 LASTPIN (-7650 5350) $PN 215
J 2
(-7660 5360);
DISPLAY 0.680851 (-7660 5360);
PAINT MONO (-7660 5360);
FORCEPROP 0 LASTPIN (-7650 4950) $PN 225
J 2
(-7660 4960);
DISPLAY 0.680851 (-7660 4960);
PAINT MONO (-7660 4960);
FORCEPROP 0 LASTPIN (-7650 5400) $PN 72
J 2
(-7660 5410);
DISPLAY 0.680851 (-7660 5410);
PAINT MONO (-7660 5410);
FORCEPROP 0 LASTPIN (-7650 5000) $PN 82
J 2
(-7660 5010);
DISPLAY 0.680851 (-7660 5010);
PAINT MONO (-7660 5010);
FORCEPROP 0 LASTPIN (-7650 3650) $PN 51
J 2
(-7660 3660);
DISPLAY 0.680851 (-7660 3660);
PAINT MONO (-7660 3660);
FORCEPROP 0 LASTPIN (-7650 3200) $PN 96
J 2
(-7660 3210);
DISPLAY 0.680851 (-7660 3210);
PAINT MONO (-7660 3210);
FORCEPROP 0 LASTPIN (-7650 3700) $PN 53
J 2
(-7660 3710);
DISPLAY 0.680851 (-7660 3710);
PAINT MONO (-7660 3710);
FORCEPROP 0 LASTPIN (-7650 3250) $PN 98
J 2
(-7660 3260);
DISPLAY 0.680851 (-7660 3260);
PAINT MONO (-7660 3260);
FORCEPROP 0 LASTPIN (-7650 3750) $PN 196
J 2
(-7660 3760);
DISPLAY 0.680851 (-7660 3760);
PAINT MONO (-7660 3760);
FORCEPROP 0 LASTPIN (-7650 3300) $PN 241
J 2
(-7660 3310);
DISPLAY 0.680851 (-7660 3310);
PAINT MONO (-7660 3310);
FORCEPROP 0 LASTPIN (-7650 3800) $PN 198
J 2
(-7660 3810);
DISPLAY 0.680851 (-7660 3810);
PAINT MONO (-7660 3810);
FORCEPROP 0 LASTPIN (-7650 3350) $PN 243
J 2
(-7660 3360);
DISPLAY 0.680851 (-7660 3360);
PAINT MONO (-7660 3360);
FORCEPROP 0 LASTPIN (-7650 3850) $PN 58
J 2
(-7660 3860);
DISPLAY 0.680851 (-7660 3860);
PAINT MONO (-7660 3860);
FORCEPROP 0 LASTPIN (-7650 3400) $PN 89
J 2
(-7660 3410);
DISPLAY 0.680851 (-7660 3410);
PAINT MONO (-7660 3410);
FORCEPROP 0 LASTPIN (-7650 3900) $PN 60
J 2
(-7660 3910);
DISPLAY 0.680851 (-7660 3910);
PAINT MONO (-7660 3910);
FORCEPROP 0 LASTPIN (-7650 3450) $PN 91
J 2
(-7660 3460);
DISPLAY 0.680851 (-7660 3460);
PAINT MONO (-7660 3460);
FORCEPROP 0 LASTPIN (-7650 3950) $PN 203
J 2
(-7660 3960);
DISPLAY 0.680851 (-7660 3960);
PAINT MONO (-7660 3960);
FORCEPROP 0 LASTPIN (-7650 3500) $PN 234
J 2
(-7660 3510);
DISPLAY 0.680851 (-7660 3510);
PAINT MONO (-7660 3510);
FORCEPROP 0 LASTPIN (-7650 4000) $PN 205
J 2
(-7660 4010);
DISPLAY 0.680851 (-7660 4010);
PAINT MONO (-7660 4010);
FORCEPROP 0 LASTPIN (-7650 3550) $PN 236
J 2
(-7660 3560);
DISPLAY 0.680851 (-7660 3560);
PAINT MONO (-7660 3560);
FORCEPROP 0 LASTPIN (-7650 4100) $PN 218
J 2
(-7660 4110);
DISPLAY 0.680851 (-7660 4110);
PAINT MONO (-7660 4110);
FORCEPROP 0 LASTPIN (-7650 4150) $PN 217
J 2
(-7660 4160);
DISPLAY 0.680851 (-7660 4160);
PAINT MONO (-7660 4160);
FORCEPROP 0 LASTPIN (-7650 4400) $PN 64
J 2
(-7660 4410);
DISPLAY 0.680851 (-7660 4410);
PAINT MONO (-7660 4410);
FORCEPROP 0 LASTPIN (-7650 4250) $PN 84
J 2
(-7660 4260);
DISPLAY 0.680851 (-7660 4260);
PAINT MONO (-7660 4260);
FORCEPROP 0 LASTPIN (-7650 4450) $PN 209
J 2
(-7660 4460);
DISPLAY 0.680851 (-7660 4460);
PAINT MONO (-7660 4460);
FORCEPROP 0 LASTPIN (-7650 4300) $PN 229
J 2
(-7660 4310);
DISPLAY 0.680851 (-7660 4310);
PAINT MONO (-7660 4310);
FORCEPROP 0 LASTPIN (-6450 3850) $PN 7
J 0
(-6440 3860);
DISPLAY 0.680851 (-6440 3860);
PAINT MONO (-6440 3860);
FORCEPROP 0 LASTPIN (-6450 2200) $PN 100
J 0
(-6440 2210);
DISPLAY 0.680851 (-6440 2210);
PAINT MONO (-6440 2210);
FORCEPROP 0 LASTPIN (-6450 3900) $PN 9
J 0
(-6440 3910);
DISPLAY 0.680851 (-6440 3910);
PAINT MONO (-6440 3910);
FORCEPROP 0 LASTPIN (-6450 2250) $PN 102
J 0
(-6440 2260);
DISPLAY 0.680851 (-6440 2260);
PAINT MONO (-6440 2260);
FORCEPROP 0 LASTPIN (-6450 3950) $PN 152
J 0
(-6440 3960);
DISPLAY 0.680851 (-6440 3960);
PAINT MONO (-6440 3960);
FORCEPROP 0 LASTPIN (-6450 2300) $PN 245
J 0
(-6440 2310);
DISPLAY 0.680851 (-6440 2310);
PAINT MONO (-6440 2310);
FORCEPROP 0 LASTPIN (-6450 4000) $PN 154
J 0
(-6440 4010);
DISPLAY 0.680851 (-6440 4010);
PAINT MONO (-6440 4010);
FORCEPROP 0 LASTPIN (-6450 2350) $PN 247
J 0
(-6440 2360);
DISPLAY 0.680851 (-6440 2360);
PAINT MONO (-6440 2360);
FORCEPROP 0 LASTPIN (-6450 4050) $PN 14
J 0
(-6440 4060);
DISPLAY 0.680851 (-6440 4060);
PAINT MONO (-6440 4060);
FORCEPROP 0 LASTPIN (-6450 2400) $PN 107
J 0
(-6440 2410);
DISPLAY 0.680851 (-6440 2410);
PAINT MONO (-6440 2410);
FORCEPROP 0 LASTPIN (-6450 4100) $PN 16
J 0
(-6440 4110);
DISPLAY 0.680851 (-6440 4110);
PAINT MONO (-6440 4110);
FORCEPROP 0 LASTPIN (-6450 2450) $PN 109
J 0
(-6440 2460);
DISPLAY 0.680851 (-6440 2460);
PAINT MONO (-6440 2460);
FORCEPROP 0 LASTPIN (-6450 4150) $PN 159
J 0
(-6440 4160);
DISPLAY 0.680851 (-6440 4160);
PAINT MONO (-6440 4160);
FORCEPROP 0 LASTPIN (-6450 2500) $PN 252
J 0
(-6440 2510);
DISPLAY 0.680851 (-6440 2510);
PAINT MONO (-6440 2510);
FORCEPROP 0 LASTPIN (-6450 4200) $PN 161
J 0
(-6440 4210);
DISPLAY 0.680851 (-6440 4210);
PAINT MONO (-6440 4210);
FORCEPROP 0 LASTPIN (-6450 2550) $PN 254
J 0
(-6440 2560);
DISPLAY 0.680851 (-6440 2560);
PAINT MONO (-6440 2560);
FORCEPROP 0 LASTPIN (-6450 4250) $PN 18
J 0
(-6440 4260);
DISPLAY 0.680851 (-6440 4260);
PAINT MONO (-6440 4260);
FORCEPROP 0 LASTPIN (-6450 2600) $PN 111
J 0
(-6440 2610);
DISPLAY 0.680851 (-6440 2610);
PAINT MONO (-6440 2610);
FORCEPROP 0 LASTPIN (-6450 4300) $PN 20
J 0
(-6440 4310);
DISPLAY 0.680851 (-6440 4310);
PAINT MONO (-6440 4310);
FORCEPROP 0 LASTPIN (-6450 2650) $PN 113
J 0
(-6440 2660);
DISPLAY 0.680851 (-6440 2660);
PAINT MONO (-6440 2660);
FORCEPROP 0 LASTPIN (-6450 4350) $PN 163
J 0
(-6440 4360);
DISPLAY 0.680851 (-6440 4360);
PAINT MONO (-6440 4360);
FORCEPROP 0 LASTPIN (-6450 2700) $PN 256
J 0
(-6440 2710);
DISPLAY 0.680851 (-6440 2710);
PAINT MONO (-6440 2710);
FORCEPROP 0 LASTPIN (-6450 4400) $PN 165
J 0
(-6440 4410);
DISPLAY 0.680851 (-6440 4410);
PAINT MONO (-6440 4410);
FORCEPROP 0 LASTPIN (-6450 2750) $PN 258
J 0
(-6440 2760);
DISPLAY 0.680851 (-6440 2760);
PAINT MONO (-6440 2760);
FORCEPROP 0 LASTPIN (-6450 4450) $PN 25
J 0
(-6440 4460);
DISPLAY 0.680851 (-6440 4460);
PAINT MONO (-6440 4460);
FORCEPROP 0 LASTPIN (-6450 2800) $PN 118
J 0
(-6440 2810);
DISPLAY 0.680851 (-6440 2810);
PAINT MONO (-6440 2810);
FORCEPROP 0 LASTPIN (-6450 4500) $PN 27
J 0
(-6440 4510);
DISPLAY 0.680851 (-6440 4510);
PAINT MONO (-6440 4510);
FORCEPROP 0 LASTPIN (-6450 2850) $PN 120
J 0
(-6440 2860);
DISPLAY 0.680851 (-6440 2860);
PAINT MONO (-6440 2860);
FORCEPROP 0 LASTPIN (-6450 4550) $PN 170
J 0
(-6440 4560);
DISPLAY 0.680851 (-6440 4560);
PAINT MONO (-6440 4560);
FORCEPROP 0 LASTPIN (-6450 2900) $PN 263
J 0
(-6440 2910);
DISPLAY 0.680851 (-6440 2910);
PAINT MONO (-6440 2910);
FORCEPROP 0 LASTPIN (-6450 4600) $PN 172
J 0
(-6440 4610);
DISPLAY 0.680851 (-6440 4610);
PAINT MONO (-6440 4610);
FORCEPROP 0 LASTPIN (-6450 2950) $PN 265
J 0
(-6440 2960);
DISPLAY 0.680851 (-6440 2960);
PAINT MONO (-6440 2960);
FORCEPROP 0 LASTPIN (-6450 4650) $PN 29
J 0
(-6440 4660);
DISPLAY 0.680851 (-6440 4660);
PAINT MONO (-6440 4660);
FORCEPROP 0 LASTPIN (-6450 3000) $PN 122
J 0
(-6440 3010);
DISPLAY 0.680851 (-6440 3010);
PAINT MONO (-6440 3010);
FORCEPROP 0 LASTPIN (-6450 4700) $PN 31
J 0
(-6440 4710);
DISPLAY 0.680851 (-6440 4710);
PAINT MONO (-6440 4710);
FORCEPROP 0 LASTPIN (-6450 3050) $PN 124
J 0
(-6440 3060);
DISPLAY 0.680851 (-6440 3060);
PAINT MONO (-6440 3060);
FORCEPROP 0 LASTPIN (-6450 4750) $PN 174
J 0
(-6440 4760);
DISPLAY 0.680851 (-6440 4760);
PAINT MONO (-6440 4760);
FORCEPROP 0 LASTPIN (-6450 3100) $PN 267
J 0
(-6440 3110);
DISPLAY 0.680851 (-6440 3110);
PAINT MONO (-6440 3110);
FORCEPROP 0 LASTPIN (-6450 4800) $PN 176
J 0
(-6440 4810);
DISPLAY 0.680851 (-6440 4810);
PAINT MONO (-6440 4810);
FORCEPROP 0 LASTPIN (-6450 3150) $PN 269
J 0
(-6440 3160);
DISPLAY 0.680851 (-6440 3160);
PAINT MONO (-6440 3160);
FORCEPROP 0 LASTPIN (-6450 4850) $PN 36
J 0
(-6440 4860);
DISPLAY 0.680851 (-6440 4860);
PAINT MONO (-6440 4860);
FORCEPROP 0 LASTPIN (-6450 3200) $PN 129
J 0
(-6440 3210);
DISPLAY 0.680851 (-6440 3210);
PAINT MONO (-6440 3210);
FORCEPROP 0 LASTPIN (-6450 4900) $PN 38
J 0
(-6440 4910);
DISPLAY 0.680851 (-6440 4910);
PAINT MONO (-6440 4910);
FORCEPROP 0 LASTPIN (-6450 3250) $PN 131
J 0
(-6440 3260);
DISPLAY 0.680851 (-6440 3260);
PAINT MONO (-6440 3260);
FORCEPROP 0 LASTPIN (-6450 4950) $PN 181
J 0
(-6440 4960);
DISPLAY 0.680851 (-6440 4960);
PAINT MONO (-6440 4960);
FORCEPROP 0 LASTPIN (-6450 3300) $PN 274
J 0
(-6440 3310);
DISPLAY 0.680851 (-6440 3310);
PAINT MONO (-6440 3310);
FORCEPROP 0 LASTPIN (-6450 5000) $PN 183
J 0
(-6440 5010);
DISPLAY 0.680851 (-6440 5010);
PAINT MONO (-6440 5010);
FORCEPROP 0 LASTPIN (-6450 3350) $PN 276
J 0
(-6440 3360);
DISPLAY 0.680851 (-6440 3360);
PAINT MONO (-6440 3360);
FORCEPROP 0 LASTPIN (-6450 5050) $PN 40
J 0
(-6440 5060);
DISPLAY 0.680851 (-6440 5060);
PAINT MONO (-6440 5060);
FORCEPROP 0 LASTPIN (-6450 3400) $PN 133
J 0
(-6440 3410);
DISPLAY 0.680851 (-6440 3410);
PAINT MONO (-6440 3410);
FORCEPROP 0 LASTPIN (-6450 5100) $PN 42
J 0
(-6440 5110);
DISPLAY 0.680851 (-6440 5110);
PAINT MONO (-6440 5110);
FORCEPROP 0 LASTPIN (-6450 3450) $PN 135
J 0
(-6440 3460);
DISPLAY 0.680851 (-6440 3460);
PAINT MONO (-6440 3460);
FORCEPROP 0 LASTPIN (-6450 5150) $PN 185
J 0
(-6440 5160);
DISPLAY 0.680851 (-6440 5160);
PAINT MONO (-6440 5160);
FORCEPROP 0 LASTPIN (-6450 3500) $PN 278
J 0
(-6440 3510);
DISPLAY 0.680851 (-6440 3510);
PAINT MONO (-6440 3510);
FORCEPROP 0 LASTPIN (-6450 5200) $PN 187
J 0
(-6440 5210);
DISPLAY 0.680851 (-6440 5210);
PAINT MONO (-6440 5210);
FORCEPROP 0 LASTPIN (-6450 3550) $PN 280
J 0
(-6440 3560);
DISPLAY 0.680851 (-6440 3560);
PAINT MONO (-6440 3560);
FORCEPROP 0 LASTPIN (-6450 5250) $PN 47
J 0
(-6440 5260);
DISPLAY 0.680851 (-6440 5260);
PAINT MONO (-6440 5260);
FORCEPROP 0 LASTPIN (-6450 3600) $PN 140
J 0
(-6440 3610);
DISPLAY 0.680851 (-6440 3610);
PAINT MONO (-6440 3610);
FORCEPROP 0 LASTPIN (-6450 5300) $PN 49
J 0
(-6440 5310);
DISPLAY 0.680851 (-6440 5310);
PAINT MONO (-6440 5310);
FORCEPROP 0 LASTPIN (-6450 3650) $PN 142
J 0
(-6440 3660);
DISPLAY 0.680851 (-6440 3660);
PAINT MONO (-6440 3660);
FORCEPROP 0 LASTPIN (-6450 5350) $PN 192
J 0
(-6440 5360);
DISPLAY 0.680851 (-6440 5360);
PAINT MONO (-6440 5360);
FORCEPROP 0 LASTPIN (-6450 3700) $PN 285
J 0
(-6440 3710);
DISPLAY 0.680851 (-6440 3710);
PAINT MONO (-6440 3710);
FORCEPROP 0 LASTPIN (-6450 5400) $PN 194
J 0
(-6440 5410);
DISPLAY 0.680851 (-6440 5410);
PAINT MONO (-6440 5410);
FORCEPROP 0 LASTPIN (-6450 3750) $PN 287
J 0
(-6440 3760);
DISPLAY 0.680851 (-6440 3760);
PAINT MONO (-6440 3760);
FORCEPROP 0 LASTPIN (-7650 2900) $PN 148
J 2
(-7660 2910);
DISPLAY 0.680851 (-7660 2910);
PAINT MONO (-7660 2910);
FORCEPROP 0 LASTPIN (-7650 2800) $PN 4
J 2
(-7660 2810);
DISPLAY 0.680851 (-7660 2810);
PAINT MONO (-7660 2810);
FORCEPROP 0 LASTPIN (-7650 2850) $PN 5
J 2
(-7660 2860);
DISPLAY 0.680851 (-7660 2860);
PAINT MONO (-7660 2860);
FORCEPROP 0 LASTPIN (-7650 2000) $PN 86
J 2
(-7660 2010);
DISPLAY 0.680851 (-7660 2010);
PAINT MONO (-7660 2010);
FORCEPROP 0 LASTPIN (-7650 1950) $PN 87
J 2
(-7660 1960);
DISPLAY 0.680851 (-7660 1960);
PAINT MONO (-7660 1960);
FORCEPROP 0 LASTPIN (-7650 4600) $PN 74
J 2
(-7660 4610);
DISPLAY 0.680851 (-7660 4610);
PAINT MONO (-7660 4610);
FORCEPROP 0 LASTPIN (-7650 4550) $PN 227
J 2
(-7660 4560);
DISPLAY 0.680851 (-7660 4560);
PAINT MONO (-7660 4560);
FORCEPROP 0 LASTPIN (-7650 2550) $PN 147
J 2
(-7660 2560);
DISPLAY 0.680851 (-7660 2560);
PAINT MONO (-7660 2560);
FORCEPROP 0 LASTPIN (-7650 3100) $PN 207
J 2
(-7660 3110);
DISPLAY 0.680851 (-7660 3110);
PAINT MONO (-7660 3110);
FORCEPROP 0 LASTPIN (-7650 2150) $PN 2
J 2
(-7660 2160);
DISPLAY 0.680851 (-7660 2160);
PAINT MONO (-7660 2160);
FORCEPROP 0 LASTPIN (-7650 2200) $PN 144
J 2
(-7660 2210);
DISPLAY 0.680851 (-7660 2210);
PAINT MONO (-7660 2210);
FORCEPROP 0 LASTPIN (-7650 2250) $PN 149
J 2
(-7660 2260);
DISPLAY 0.680851 (-7660 2260);
PAINT MONO (-7660 2260);
FORCEPROP 0 LASTPIN (-7650 2300) $PN 150
J 2
(-7660 2310);
DISPLAY 0.680851 (-7660 2310);
PAINT MONO (-7660 2310);
FORCEPROP 0 LASTPIN (-7650 2350) $PN 220
J 2
(-7660 2360);
DISPLAY 0.680851 (-7660 2360);
PAINT MONO (-7660 2360);
FORCEPROP 0 LASTPIN (-7650 2400) $PN 231
J 2
(-7660 2410);
DISPLAY 0.680851 (-7660 2410);
PAINT MONO (-7660 2410);
FORCEPROP 0 LASTPIN (-7650 2450) $PN 232
J 2
(-7660 2460);
DISPLAY 0.680851 (-7660 2460);
PAINT MONO (-7660 2460);
FORCEPROP 0 LASTPIN (-7650 2950) $PN 3
J 2
(-7660 2960);
DISPLAY 0.680851 (-7660 2960);
PAINT MONO (-7660 2960);
FORCEPROP 2 LAST PART_TYPE SMLF
J 0
(-7500 5825);
DISPLAY 1.021277 (-7500 5825);
FORCEPROP 2 LAST VALUE SCONN288_DDR506112002KQ
J 0
(-7500 5775);
DISPLAY 0.489362 (-7500 5775);
PAINT SKYBLUE (-7500 5775);
FORCEPROP 1 LAST MATERIAL IO
J 0
(-7500 5575);
DISPLAY 0.468085 (-7500 5575);
PAINT SKYBLUE (-7500 5575);
FORCEPROP 1 LAST CDS_LMAN_SYM_OUTLINE -450,1900,450,-1850
J 0
(-7050 3650);
DISPLAY 0.468085 (-7050 3650);
PAINT GREEN (-7050 3650);
DISPLAY INVISIBLE (-7050 3650);
FORCEPROP 1 LAST NEEDS_NO_SIZE TRUE
J 0
(-7050 3650);
DISPLAY 0.723404 (-7050 3650);
PAINT GREEN (-7050 3650);
DISPLAY INVISIBLE (-7050 3650);
FORCEPROP 2 LAST CDS_LIB pure_quanta
J 0
(-7050 3650);
DISPLAY INVISIBLE (-7050 3650);
FORCEPROP 1 LAST PATH I22
J 0
(-7050 3650);
DISPLAY 0.723404 (-7050 3650);
PAINT GREEN (-7050 3650);
DISPLAY INVISIBLE (-7050 3650);
FORCEPROP 1 LAST PART_NUMBER DFHST8FS479
J 0
(-7500 5650);
DISPLAY 0.468085 (-7500 5650);
PAINT SKYBLUE (-7500 5650);
DISPLAY INVISIBLE (-7500 5650);
FORCEADD TAP..1
(-3550 3300);
FORCEPROP 3 LASTPIN (-3600 3300) SIG_NAME M_C_CPU1_SB_DQS_DP<7>
J 0
(-3590 3310);
DISPLAY 0.659574 (-3590 3310);
PAINT MONO (-3590 3310);
DISPLAY INVISIBLE (-3590 3310);
FORCEPROP 1 LASTPIN (-3600 3300) BN 7
J 0
(-3612 3308);
DISPLAY 0.489362 (-3612 3308);
PAINT GREEN (-3612 3308);
FORCEPROP 2 LAST CDS_LIB mstr_standard
J 0
(-3550 3300);
DISPLAY 0.723404 (-3550 3300);
PAINT MONO (-3550 3300);
DISPLAY INVISIBLE (-3550 3300);
FORCEPROP 1 LAST BODY_TYPE PLUMBING
J 0
(-3550 3350);
DISPLAY 0.872340 (-3550 3350);
PAINT GREEN (-3550 3350);
DISPLAY INVISIBLE (-3550 3350);
FORCEPROP 1 LAST HDL_TAP TRUE
J 0
(-3225 3175);
DISPLAY 0.872340 (-3225 3175);
DISPLAY INVISIBLE (-3225 3175);
FORCEPROP 1 LAST PATH I220
J 0
(-3552 3300);
DISPLAY 0.872340 (-3552 3300);
PAINT GREEN (-3552 3300);
DISPLAY INVISIBLE (-3552 3300);
FORCEADD TAP..1
(-3350 3050);
FORCEPROP 3 LASTPIN (-3400 3050) SIG_NAME M_C_CPU1_SB_DQS_DN<5>
J 0
(-3390 3060);
DISPLAY 0.659574 (-3390 3060);
PAINT MONO (-3390 3060);
DISPLAY INVISIBLE (-3390 3060);
FORCEPROP 1 LASTPIN (-3400 3050) BN 5
J 0
(-3412 3058);
DISPLAY 0.489362 (-3412 3058);
PAINT GREEN (-3412 3058);
FORCEPROP 2 LAST CDS_LIB mstr_standard
J 0
(-3350 3050);
DISPLAY 0.723404 (-3350 3050);
PAINT MONO (-3350 3050);
DISPLAY INVISIBLE (-3350 3050);
FORCEPROP 1 LAST BODY_TYPE PLUMBING
J 0
(-3350 3100);
DISPLAY 0.872340 (-3350 3100);
PAINT GREEN (-3350 3100);
DISPLAY INVISIBLE (-3350 3100);
FORCEPROP 1 LAST HDL_TAP TRUE
J 0
(-3025 2925);
DISPLAY 0.872340 (-3025 2925);
DISPLAY INVISIBLE (-3025 2925);
FORCEPROP 1 LAST PATH I221
J 0
(-3352 3050);
DISPLAY 0.872340 (-3352 3050);
PAINT GREEN (-3352 3050);
DISPLAY INVISIBLE (-3352 3050);
FORCEADD TAP..1
(-3350 3250);
FORCEPROP 3 LASTPIN (-3400 3250) SIG_NAME M_C_CPU1_SB_DQS_DN<7>
J 0
(-3390 3260);
DISPLAY 0.659574 (-3390 3260);
PAINT MONO (-3390 3260);
DISPLAY INVISIBLE (-3390 3260);
FORCEPROP 1 LASTPIN (-3400 3250) BN 7
J 0
(-3412 3258);
DISPLAY 0.489362 (-3412 3258);
PAINT GREEN (-3412 3258);
FORCEPROP 2 LAST CDS_LIB mstr_standard
J 0
(-3350 3250);
DISPLAY 0.723404 (-3350 3250);
PAINT MONO (-3350 3250);
DISPLAY INVISIBLE (-3350 3250);
FORCEPROP 1 LAST BODY_TYPE PLUMBING
J 0
(-3350 3300);
DISPLAY 0.872340 (-3350 3300);
PAINT GREEN (-3350 3300);
DISPLAY INVISIBLE (-3350 3300);
FORCEPROP 1 LAST HDL_TAP TRUE
J 0
(-3025 3125);
DISPLAY 0.872340 (-3025 3125);
DISPLAY INVISIBLE (-3025 3125);
FORCEPROP 1 LAST PATH I222
J 0
(-3352 3250);
DISPLAY 0.872340 (-3352 3250);
PAINT GREEN (-3352 3250);
DISPLAY INVISIBLE (-3352 3250);
FORCEADD TAP..1
(-3350 3150);
FORCEPROP 3 LASTPIN (-3400 3150) SIG_NAME M_C_CPU1_SB_DQS_DN<6>
J 0
(-3390 3160);
DISPLAY 0.659574 (-3390 3160);
PAINT MONO (-3390 3160);
DISPLAY INVISIBLE (-3390 3160);
FORCEPROP 1 LASTPIN (-3400 3150) BN 6
J 0
(-3412 3158);
DISPLAY 0.489362 (-3412 3158);
PAINT GREEN (-3412 3158);
FORCEPROP 2 LAST CDS_LIB mstr_standard
J 0
(-3350 3150);
DISPLAY 0.723404 (-3350 3150);
PAINT MONO (-3350 3150);
DISPLAY INVISIBLE (-3350 3150);
FORCEPROP 1 LAST BODY_TYPE PLUMBING
J 0
(-3350 3200);
DISPLAY 0.872340 (-3350 3200);
PAINT GREEN (-3350 3200);
DISPLAY INVISIBLE (-3350 3200);
FORCEPROP 1 LAST HDL_TAP TRUE
J 0
(-3025 3025);
DISPLAY 0.872340 (-3025 3025);
DISPLAY INVISIBLE (-3025 3025);
FORCEPROP 1 LAST PATH I223
J 0
(-3352 3150);
DISPLAY 0.872340 (-3352 3150);
PAINT GREEN (-3352 3150);
DISPLAY INVISIBLE (-3352 3150);
FORCEADD TAP..1
(-3550 3200);
FORCEPROP 3 LASTPIN (-3600 3200) SIG_NAME M_C_CPU1_SB_DQS_DP<6>
J 0
(-3590 3210);
DISPLAY 0.659574 (-3590 3210);
PAINT MONO (-3590 3210);
DISPLAY INVISIBLE (-3590 3210);
FORCEPROP 1 LASTPIN (-3600 3200) BN 6
J 0
(-3612 3208);
DISPLAY 0.489362 (-3612 3208);
PAINT GREEN (-3612 3208);
FORCEPROP 2 LAST CDS_LIB mstr_standard
J 0
(-3550 3200);
DISPLAY 0.723404 (-3550 3200);
PAINT MONO (-3550 3200);
DISPLAY INVISIBLE (-3550 3200);
FORCEPROP 1 LAST BODY_TYPE PLUMBING
J 0
(-3550 3250);
DISPLAY 0.872340 (-3550 3250);
PAINT GREEN (-3550 3250);
DISPLAY INVISIBLE (-3550 3250);
FORCEPROP 1 LAST HDL_TAP TRUE
J 0
(-3225 3075);
DISPLAY 0.872340 (-3225 3075);
DISPLAY INVISIBLE (-3225 3075);
FORCEPROP 1 LAST PATH I224
J 0
(-3552 3200);
DISPLAY 0.872340 (-3552 3200);
PAINT GREEN (-3552 3200);
DISPLAY INVISIBLE (-3552 3200);
FORCEADD TAP..1
(-3550 3100);
FORCEPROP 3 LASTPIN (-3600 3100) SIG_NAME M_C_CPU1_SB_DQS_DP<5>
J 0
(-3590 3110);
DISPLAY 0.659574 (-3590 3110);
PAINT MONO (-3590 3110);
DISPLAY INVISIBLE (-3590 3110);
FORCEPROP 1 LASTPIN (-3600 3100) BN 5
J 0
(-3612 3108);
DISPLAY 0.489362 (-3612 3108);
PAINT GREEN (-3612 3108);
FORCEPROP 2 LAST CDS_LIB mstr_standard
J 0
(-3550 3100);
DISPLAY 0.723404 (-3550 3100);
PAINT MONO (-3550 3100);
DISPLAY INVISIBLE (-3550 3100);
FORCEPROP 1 LAST BODY_TYPE PLUMBING
J 0
(-3550 3150);
DISPLAY 0.872340 (-3550 3150);
PAINT GREEN (-3550 3150);
DISPLAY INVISIBLE (-3550 3150);
FORCEPROP 1 LAST HDL_TAP TRUE
J 0
(-3225 2975);
DISPLAY 0.872340 (-3225 2975);
DISPLAY INVISIBLE (-3225 2975);
FORCEPROP 1 LAST PATH I225
J 0
(-3552 3100);
DISPLAY 0.872340 (-3552 3100);
PAINT GREEN (-3552 3100);
DISPLAY INVISIBLE (-3552 3100);
FORCEADD TAP..1
(-3350 2950);
FORCEPROP 3 LASTPIN (-3400 2950) SIG_NAME M_C_CPU1_SB_DQS_DN<4>
J 0
(-3390 2960);
DISPLAY 0.659574 (-3390 2960);
PAINT MONO (-3390 2960);
DISPLAY INVISIBLE (-3390 2960);
FORCEPROP 1 LASTPIN (-3400 2950) BN 4
J 0
(-3412 2958);
DISPLAY 0.489362 (-3412 2958);
PAINT GREEN (-3412 2958);
FORCEPROP 2 LAST CDS_LIB mstr_standard
J 0
(-3350 2950);
DISPLAY 0.723404 (-3350 2950);
PAINT MONO (-3350 2950);
DISPLAY INVISIBLE (-3350 2950);
FORCEPROP 1 LAST BODY_TYPE PLUMBING
J 0
(-3350 3000);
DISPLAY 0.872340 (-3350 3000);
PAINT GREEN (-3350 3000);
DISPLAY INVISIBLE (-3350 3000);
FORCEPROP 1 LAST HDL_TAP TRUE
J 0
(-3025 2825);
DISPLAY 0.872340 (-3025 2825);
DISPLAY INVISIBLE (-3025 2825);
FORCEPROP 1 LAST PATH I226
J 0
(-3352 2950);
DISPLAY 0.872340 (-3352 2950);
PAINT GREEN (-3352 2950);
DISPLAY INVISIBLE (-3352 2950);
FORCEADD TAP..1
(-3350 2850);
FORCEPROP 3 LASTPIN (-3400 2850) SIG_NAME M_C_CPU1_SB_DQS_DN<3>
J 0
(-3390 2860);
DISPLAY 0.659574 (-3390 2860);
PAINT MONO (-3390 2860);
DISPLAY INVISIBLE (-3390 2860);
FORCEPROP 1 LASTPIN (-3400 2850) BN 3
J 0
(-3412 2858);
DISPLAY 0.489362 (-3412 2858);
PAINT GREEN (-3412 2858);
FORCEPROP 2 LAST CDS_LIB mstr_standard
J 0
(-3350 2850);
DISPLAY 0.723404 (-3350 2850);
PAINT MONO (-3350 2850);
DISPLAY INVISIBLE (-3350 2850);
FORCEPROP 1 LAST BODY_TYPE PLUMBING
J 0
(-3350 2900);
DISPLAY 0.872340 (-3350 2900);
PAINT GREEN (-3350 2900);
DISPLAY INVISIBLE (-3350 2900);
FORCEPROP 1 LAST HDL_TAP TRUE
J 0
(-3025 2725);
DISPLAY 0.872340 (-3025 2725);
DISPLAY INVISIBLE (-3025 2725);
FORCEPROP 1 LAST PATH I227
J 0
(-3352 2850);
DISPLAY 0.872340 (-3352 2850);
PAINT GREEN (-3352 2850);
DISPLAY INVISIBLE (-3352 2850);
FORCEADD TAP..1
(-3550 3000);
FORCEPROP 3 LASTPIN (-3600 3000) SIG_NAME M_C_CPU1_SB_DQS_DP<4>
J 0
(-3590 3010);
DISPLAY 0.659574 (-3590 3010);
PAINT MONO (-3590 3010);
DISPLAY INVISIBLE (-3590 3010);
FORCEPROP 1 LASTPIN (-3600 3000) BN 4
J 0
(-3612 3008);
DISPLAY 0.489362 (-3612 3008);
PAINT GREEN (-3612 3008);
FORCEPROP 2 LAST CDS_LIB mstr_standard
J 0
(-3550 3000);
DISPLAY 0.723404 (-3550 3000);
PAINT MONO (-3550 3000);
DISPLAY INVISIBLE (-3550 3000);
FORCEPROP 1 LAST BODY_TYPE PLUMBING
J 0
(-3550 3050);
DISPLAY 0.872340 (-3550 3050);
PAINT GREEN (-3550 3050);
DISPLAY INVISIBLE (-3550 3050);
FORCEPROP 1 LAST HDL_TAP TRUE
J 0
(-3225 2875);
DISPLAY 0.872340 (-3225 2875);
DISPLAY INVISIBLE (-3225 2875);
FORCEPROP 1 LAST PATH I228
J 0
(-3552 3000);
DISPLAY 0.872340 (-3552 3000);
PAINT GREEN (-3552 3000);
DISPLAY INVISIBLE (-3552 3000);
FORCEADD TAP..1
(-3550 2800);
FORCEPROP 3 LASTPIN (-3600 2800) SIG_NAME M_C_CPU1_SB_DQS_DP<2>
J 0
(-3590 2810);
DISPLAY 0.659574 (-3590 2810);
PAINT MONO (-3590 2810);
DISPLAY INVISIBLE (-3590 2810);
FORCEPROP 1 LASTPIN (-3600 2800) BN 2
J 0
(-3612 2808);
DISPLAY 0.489362 (-3612 2808);
PAINT GREEN (-3612 2808);
FORCEPROP 2 LAST CDS_LIB mstr_standard
J 0
(-3550 2800);
DISPLAY 0.723404 (-3550 2800);
PAINT MONO (-3550 2800);
DISPLAY INVISIBLE (-3550 2800);
FORCEPROP 1 LAST BODY_TYPE PLUMBING
J 0
(-3550 2850);
DISPLAY 0.872340 (-3550 2850);
PAINT GREEN (-3550 2850);
DISPLAY INVISIBLE (-3550 2850);
FORCEPROP 1 LAST HDL_TAP TRUE
J 0
(-3225 2675);
DISPLAY 0.872340 (-3225 2675);
DISPLAY INVISIBLE (-3225 2675);
FORCEPROP 1 LAST PATH I229
J 0
(-3552 2800);
DISPLAY 0.872340 (-3552 2800);
PAINT GREEN (-3552 2800);
DISPLAY INVISIBLE (-3552 2800);
FORCEADD TAP..1
R 2
(-7900 3200);
FORCEPROP 3 LASTPIN (-7850 3200) SIG_NAME M_C_CPU1_SB_CB<0>
J 0
(-7840 3210);
DISPLAY 0.659574 (-7840 3210);
PAINT MONO (-7840 3210);
DISPLAY INVISIBLE (-7840 3210);
FORCEPROP 1 LASTPIN (-7850 3200) BN 0
J 2
(-7838 3208);
DISPLAY 0.489362 (-7838 3208);
PAINT GREEN (-7838 3208);
FORCEPROP 2 LAST CDS_LIB mstr_standard
J 0
(-7900 3200);
DISPLAY 0.723404 (-7900 3200);
PAINT MONO (-7900 3200);
DISPLAY INVISIBLE (-7900 3200);
FORCEPROP 1 LAST BODY_TYPE PLUMBING
J 2
(-7900 3250);
DISPLAY 0.872340 (-7900 3250);
PAINT GREEN (-7900 3250);
DISPLAY INVISIBLE (-7900 3250);
FORCEPROP 1 LAST HDL_TAP TRUE
J 2
(-8225 3075);
DISPLAY 0.872340 (-8225 3075);
DISPLAY INVISIBLE (-8225 3075);
FORCEPROP 1 LAST PATH I23
J 2
(-7898 3200);
DISPLAY 0.872340 (-7898 3200);
PAINT GREEN (-7898 3200);
DISPLAY INVISIBLE (-7898 3200);
FORCEADD TAP..1
(-3550 2900);
FORCEPROP 3 LASTPIN (-3600 2900) SIG_NAME M_C_CPU1_SB_DQS_DP<3>
J 0
(-3590 2910);
DISPLAY 0.659574 (-3590 2910);
PAINT MONO (-3590 2910);
DISPLAY INVISIBLE (-3590 2910);
FORCEPROP 1 LASTPIN (-3600 2900) BN 3
J 0
(-3612 2908);
DISPLAY 0.489362 (-3612 2908);
PAINT GREEN (-3612 2908);
FORCEPROP 2 LAST CDS_LIB mstr_standard
J 0
(-3550 2900);
DISPLAY 0.723404 (-3550 2900);
PAINT MONO (-3550 2900);
DISPLAY INVISIBLE (-3550 2900);
FORCEPROP 1 LAST BODY_TYPE PLUMBING
J 0
(-3550 2950);
DISPLAY 0.872340 (-3550 2950);
PAINT GREEN (-3550 2950);
DISPLAY INVISIBLE (-3550 2950);
FORCEPROP 1 LAST HDL_TAP TRUE
J 0
(-3225 2775);
DISPLAY 0.872340 (-3225 2775);
DISPLAY INVISIBLE (-3225 2775);
FORCEPROP 1 LAST PATH I230
J 0
(-3552 2900);
DISPLAY 0.872340 (-3552 2900);
PAINT GREEN (-3552 2900);
DISPLAY INVISIBLE (-3552 2900);
FORCEADD TAP..1
(-3350 2550);
FORCEPROP 3 LASTPIN (-3400 2550) SIG_NAME M_C_CPU1_SB_DQS_DN<0>
J 0
(-3390 2560);
DISPLAY 0.659574 (-3390 2560);
PAINT MONO (-3390 2560);
DISPLAY INVISIBLE (-3390 2560);
FORCEPROP 1 LASTPIN (-3400 2550) BN 0
J 0
(-3412 2558);
DISPLAY 0.489362 (-3412 2558);
PAINT GREEN (-3412 2558);
FORCEPROP 2 LAST CDS_LIB mstr_standard
J 0
(-3350 2550);
DISPLAY 0.723404 (-3350 2550);
PAINT MONO (-3350 2550);
DISPLAY INVISIBLE (-3350 2550);
FORCEPROP 1 LAST BODY_TYPE PLUMBING
J 0
(-3350 2600);
DISPLAY 0.872340 (-3350 2600);
PAINT GREEN (-3350 2600);
DISPLAY INVISIBLE (-3350 2600);
FORCEPROP 1 LAST HDL_TAP TRUE
J 0
(-3025 2425);
DISPLAY 0.872340 (-3025 2425);
DISPLAY INVISIBLE (-3025 2425);
FORCEPROP 1 LAST PATH I231
J 0
(-3352 2550);
DISPLAY 0.872340 (-3352 2550);
PAINT GREEN (-3352 2550);
DISPLAY INVISIBLE (-3352 2550);
FORCEADD TAP..1
(-3350 2650);
FORCEPROP 3 LASTPIN (-3400 2650) SIG_NAME M_C_CPU1_SB_DQS_DN<1>
J 0
(-3390 2660);
DISPLAY 0.659574 (-3390 2660);
PAINT MONO (-3390 2660);
DISPLAY INVISIBLE (-3390 2660);
FORCEPROP 1 LASTPIN (-3400 2650) BN 1
J 0
(-3412 2658);
DISPLAY 0.489362 (-3412 2658);
PAINT GREEN (-3412 2658);
FORCEPROP 2 LAST CDS_LIB mstr_standard
J 0
(-3350 2650);
DISPLAY 0.723404 (-3350 2650);
PAINT MONO (-3350 2650);
DISPLAY INVISIBLE (-3350 2650);
FORCEPROP 1 LAST BODY_TYPE PLUMBING
J 0
(-3350 2700);
DISPLAY 0.872340 (-3350 2700);
PAINT GREEN (-3350 2700);
DISPLAY INVISIBLE (-3350 2700);
FORCEPROP 1 LAST HDL_TAP TRUE
J 0
(-3025 2525);
DISPLAY 0.872340 (-3025 2525);
DISPLAY INVISIBLE (-3025 2525);
FORCEPROP 1 LAST PATH I232
J 0
(-3352 2650);
DISPLAY 0.872340 (-3352 2650);
PAINT GREEN (-3352 2650);
DISPLAY INVISIBLE (-3352 2650);
FORCEADD TAP..1
(-3350 2750);
FORCEPROP 3 LASTPIN (-3400 2750) SIG_NAME M_C_CPU1_SB_DQS_DN<2>
J 0
(-3390 2760);
DISPLAY 0.659574 (-3390 2760);
PAINT MONO (-3390 2760);
DISPLAY INVISIBLE (-3390 2760);
FORCEPROP 1 LASTPIN (-3400 2750) BN 2
J 0
(-3412 2758);
DISPLAY 0.489362 (-3412 2758);
PAINT GREEN (-3412 2758);
FORCEPROP 2 LAST CDS_LIB mstr_standard
J 0
(-3350 2750);
DISPLAY 0.723404 (-3350 2750);
PAINT MONO (-3350 2750);
DISPLAY INVISIBLE (-3350 2750);
FORCEPROP 1 LAST BODY_TYPE PLUMBING
J 0
(-3350 2800);
DISPLAY 0.872340 (-3350 2800);
PAINT GREEN (-3350 2800);
DISPLAY INVISIBLE (-3350 2800);
FORCEPROP 1 LAST HDL_TAP TRUE
J 0
(-3025 2625);
DISPLAY 0.872340 (-3025 2625);
DISPLAY INVISIBLE (-3025 2625);
FORCEPROP 1 LAST PATH I233
J 0
(-3352 2750);
DISPLAY 0.872340 (-3352 2750);
PAINT GREEN (-3352 2750);
DISPLAY INVISIBLE (-3352 2750);
FORCEADD TAP..1
(-3550 2700);
FORCEPROP 3 LASTPIN (-3600 2700) SIG_NAME M_C_CPU1_SB_DQS_DP<1>
J 0
(-3590 2710);
DISPLAY 0.659574 (-3590 2710);
PAINT MONO (-3590 2710);
DISPLAY INVISIBLE (-3590 2710);
FORCEPROP 1 LASTPIN (-3600 2700) BN 1
J 0
(-3612 2708);
DISPLAY 0.489362 (-3612 2708);
PAINT GREEN (-3612 2708);
FORCEPROP 2 LAST CDS_LIB mstr_standard
J 0
(-3550 2700);
DISPLAY 0.723404 (-3550 2700);
PAINT MONO (-3550 2700);
DISPLAY INVISIBLE (-3550 2700);
FORCEPROP 1 LAST BODY_TYPE PLUMBING
J 0
(-3550 2750);
DISPLAY 0.872340 (-3550 2750);
PAINT GREEN (-3550 2750);
DISPLAY INVISIBLE (-3550 2750);
FORCEPROP 1 LAST HDL_TAP TRUE
J 0
(-3225 2575);
DISPLAY 0.872340 (-3225 2575);
DISPLAY INVISIBLE (-3225 2575);
FORCEPROP 1 LAST PATH I234
J 0
(-3552 2700);
DISPLAY 0.872340 (-3552 2700);
PAINT GREEN (-3552 2700);
DISPLAY INVISIBLE (-3552 2700);
FORCEADD TAP..1
(-3550 2600);
FORCEPROP 3 LASTPIN (-3600 2600) SIG_NAME M_C_CPU1_SB_DQS_DP<0>
J 0
(-3590 2610);
DISPLAY 0.659574 (-3590 2610);
PAINT MONO (-3590 2610);
DISPLAY INVISIBLE (-3590 2610);
FORCEPROP 1 LASTPIN (-3600 2600) BN 0
J 0
(-3612 2608);
DISPLAY 0.489362 (-3612 2608);
PAINT GREEN (-3612 2608);
FORCEPROP 2 LAST CDS_LIB mstr_standard
J 0
(-3550 2600);
DISPLAY 0.723404 (-3550 2600);
PAINT MONO (-3550 2600);
DISPLAY INVISIBLE (-3550 2600);
FORCEPROP 1 LAST BODY_TYPE PLUMBING
J 0
(-3550 2650);
DISPLAY 0.872340 (-3550 2650);
PAINT GREEN (-3550 2650);
DISPLAY INVISIBLE (-3550 2650);
FORCEPROP 1 LAST HDL_TAP TRUE
J 0
(-3225 2475);
DISPLAY 0.872340 (-3225 2475);
DISPLAY INVISIBLE (-3225 2475);
FORCEPROP 1 LAST PATH I235
J 0
(-3552 2600);
DISPLAY 0.872340 (-3552 2600);
PAINT GREEN (-3552 2600);
DISPLAY INVISIBLE (-3552 2600);
FORCEADD SCONN288_DDR506112002KQ..2
(-4500 3550);
FORCEPROP 1 LAST LOCATION J28
J 0
(-5100 4875);
DISPLAY 0.468085 (-5100 4875);
PAINT SKYBLUE (-5100 4875);
FORCEPROP 0 LAST $SEC 2
J 0
(-4950 5025);
DISPLAY 0.680851 (-4950 5025);
PAINT MONO (-4950 5025);
DISPLAY INVISIBLE (-4950 5025);
FORCEPROP 0 LAST CDS_SEC 2
J 0
(-4950 5025);
DISPLAY 1.021277 (-4950 5025);
DISPLAY INVISIBLE (-4950 5025);
FORCEPROP 0 LASTPIN (-3750 3600) $PN 12
J 0
(-3740 3610);
DISPLAY 0.680851 (-3740 3610);
PAINT MONO (-3740 3610);
FORCEPROP 0 LASTPIN (-3750 3650) $PN 11
J 0
(-3740 3660);
DISPLAY 0.680851 (-3740 3660);
PAINT MONO (-3740 3660);
FORCEPROP 0 LASTPIN (-3750 2550) $PN 105
J 0
(-3740 2560);
DISPLAY 0.680851 (-3740 2560);
PAINT MONO (-3740 2560);
FORCEPROP 0 LASTPIN (-3750 2600) $PN 104
J 0
(-3740 2610);
DISPLAY 0.680851 (-3740 2610);
PAINT MONO (-3740 2610);
FORCEPROP 0 LASTPIN (-3750 3700) $PN 23
J 0
(-3740 3710);
DISPLAY 0.680851 (-3740 3710);
PAINT MONO (-3740 3710);
FORCEPROP 0 LASTPIN (-3750 3750) $PN 22
J 0
(-3740 3760);
DISPLAY 0.680851 (-3740 3760);
PAINT MONO (-3740 3760);
FORCEPROP 0 LASTPIN (-3750 2650) $PN 116
J 0
(-3740 2660);
DISPLAY 0.680851 (-3740 2660);
PAINT MONO (-3740 2660);
FORCEPROP 0 LASTPIN (-3750 2700) $PN 115
J 0
(-3740 2710);
DISPLAY 0.680851 (-3740 2710);
PAINT MONO (-3740 2710);
FORCEPROP 0 LASTPIN (-3750 3800) $PN 34
J 0
(-3740 3810);
DISPLAY 0.680851 (-3740 3810);
PAINT MONO (-3740 3810);
FORCEPROP 0 LASTPIN (-3750 3850) $PN 33
J 0
(-3740 3860);
DISPLAY 0.680851 (-3740 3860);
PAINT MONO (-3740 3860);
FORCEPROP 0 LASTPIN (-3750 2750) $PN 127
J 0
(-3740 2760);
DISPLAY 0.680851 (-3740 2760);
PAINT MONO (-3740 2760);
FORCEPROP 0 LASTPIN (-3750 2800) $PN 126
J 0
(-3740 2810);
DISPLAY 0.680851 (-3740 2810);
PAINT MONO (-3740 2810);
FORCEPROP 0 LASTPIN (-3750 3900) $PN 45
J 0
(-3740 3910);
DISPLAY 0.680851 (-3740 3910);
PAINT MONO (-3740 3910);
FORCEPROP 0 LASTPIN (-3750 3950) $PN 44
J 0
(-3740 3960);
DISPLAY 0.680851 (-3740 3960);
PAINT MONO (-3740 3960);
FORCEPROP 0 LASTPIN (-3750 2850) $PN 138
J 0
(-3740 2860);
DISPLAY 0.680851 (-3740 2860);
PAINT MONO (-3740 2860);
FORCEPROP 0 LASTPIN (-3750 2900) $PN 137
J 0
(-3740 2910);
DISPLAY 0.680851 (-3740 2910);
PAINT MONO (-3740 2910);
FORCEPROP 0 LASTPIN (-3750 4000) $PN 56
J 0
(-3740 4010);
DISPLAY 0.680851 (-3740 4010);
PAINT MONO (-3740 4010);
FORCEPROP 0 LASTPIN (-3750 4050) $PN 55
J 0
(-3740 4060);
DISPLAY 0.680851 (-3740 4060);
PAINT MONO (-3740 4060);
FORCEPROP 0 LASTPIN (-3750 2950) $PN 238
J 0
(-3740 2960);
DISPLAY 0.680851 (-3740 2960);
PAINT MONO (-3740 2960);
FORCEPROP 0 LASTPIN (-3750 3000) $PN 239
J 0
(-3740 3010);
DISPLAY 0.680851 (-3740 3010);
PAINT MONO (-3740 3010);
FORCEPROP 0 LASTPIN (-3750 4100) $PN 156
J 0
(-3740 4110);
DISPLAY 0.680851 (-3740 4110);
PAINT MONO (-3740 4110);
FORCEPROP 0 LASTPIN (-3750 4150) $PN 157
J 0
(-3740 4160);
DISPLAY 0.680851 (-3740 4160);
PAINT MONO (-3740 4160);
FORCEPROP 0 LASTPIN (-3750 3050) $PN 249
J 0
(-3740 3060);
DISPLAY 0.680851 (-3740 3060);
PAINT MONO (-3740 3060);
FORCEPROP 0 LASTPIN (-3750 3100) $PN 250
J 0
(-3740 3110);
DISPLAY 0.680851 (-3740 3110);
PAINT MONO (-3740 3110);
FORCEPROP 0 LASTPIN (-3750 4200) $PN 167
J 0
(-3740 4210);
DISPLAY 0.680851 (-3740 4210);
PAINT MONO (-3740 4210);
FORCEPROP 0 LASTPIN (-3750 4250) $PN 168
J 0
(-3740 4260);
DISPLAY 0.680851 (-3740 4260);
PAINT MONO (-3740 4260);
FORCEPROP 0 LASTPIN (-3750 3150) $PN 260
J 0
(-3740 3160);
DISPLAY 0.680851 (-3740 3160);
PAINT MONO (-3740 3160);
FORCEPROP 0 LASTPIN (-3750 3200) $PN 261
J 0
(-3740 3210);
DISPLAY 0.680851 (-3740 3210);
PAINT MONO (-3740 3210);
FORCEPROP 0 LASTPIN (-3750 4300) $PN 178
J 0
(-3740 4310);
DISPLAY 0.680851 (-3740 4310);
PAINT MONO (-3740 4310);
FORCEPROP 0 LASTPIN (-3750 4350) $PN 179
J 0
(-3740 4360);
DISPLAY 0.680851 (-3740 4360);
PAINT MONO (-3740 4360);
FORCEPROP 0 LASTPIN (-3750 3250) $PN 271
J 0
(-3740 3260);
DISPLAY 0.680851 (-3740 3260);
PAINT MONO (-3740 3260);
FORCEPROP 0 LASTPIN (-3750 3300) $PN 272
J 0
(-3740 3310);
DISPLAY 0.680851 (-3740 3310);
PAINT MONO (-3740 3310);
FORCEPROP 0 LASTPIN (-3750 4400) $PN 189
J 0
(-3740 4410);
DISPLAY 0.680851 (-3740 4410);
PAINT MONO (-3740 4410);
FORCEPROP 0 LASTPIN (-3750 4450) $PN 190
J 0
(-3740 4460);
DISPLAY 0.680851 (-3740 4460);
PAINT MONO (-3740 4460);
FORCEPROP 0 LASTPIN (-3750 3350) $PN 282
J 0
(-3740 3360);
DISPLAY 0.680851 (-3740 3360);
PAINT MONO (-3740 3360);
FORCEPROP 0 LASTPIN (-3750 3400) $PN 283
J 0
(-3740 3410);
DISPLAY 0.680851 (-3740 3410);
PAINT MONO (-3740 3410);
FORCEPROP 0 LASTPIN (-3750 4500) $PN 200
J 0
(-3740 4510);
DISPLAY 0.680851 (-3740 4510);
PAINT MONO (-3740 4510);
FORCEPROP 0 LASTPIN (-3750 4550) $PN 201
J 0
(-3740 4560);
DISPLAY 0.680851 (-3740 4560);
PAINT MONO (-3740 4560);
FORCEPROP 0 LASTPIN (-3750 3450) $PN 94
J 0
(-3740 3460);
DISPLAY 0.680851 (-3740 3460);
PAINT MONO (-3740 3460);
FORCEPROP 0 LASTPIN (-3750 3500) $PN 93
J 0
(-3740 3510);
DISPLAY 0.680851 (-3740 3510);
PAINT MONO (-3740 3510);
FORCEPROP 2 LAST PART_TYPE SMLF
J 0
(-4950 4975);
DISPLAY 1.021277 (-4950 4975);
FORCEPROP 1 LAST MATERIAL IO
J 0
(-5100 4725);
DISPLAY 0.468085 (-5100 4725);
PAINT SKYBLUE (-5100 4725);
FORCEPROP 2 LAST VALUE SCONN288_DDR506112002KQ
J 0
(-4950 4925);
DISPLAY 0.489362 (-4950 4925);
PAINT SKYBLUE (-4950 4925);
FORCEPROP 1 LAST CDS_LMAN_SYM_OUTLINE -600,1150,600,-1150
J 0
(-4500 3550);
DISPLAY 0.468085 (-4500 3550);
PAINT GREEN (-4500 3550);
DISPLAY INVISIBLE (-4500 3550);
FORCEPROP 1 LAST NEEDS_NO_SIZE TRUE
J 0
(-4500 3550);
DISPLAY 0.723404 (-4500 3550);
PAINT GREEN (-4500 3550);
DISPLAY INVISIBLE (-4500 3550);
FORCEPROP 2 LAST CDS_LIB pure_quanta
J 0
(-4500 3550);
DISPLAY INVISIBLE (-4500 3550);
FORCEPROP 1 LAST PATH I236
J 0
(-4500 3550);
DISPLAY 0.723404 (-4500 3550);
PAINT GREEN (-4500 3550);
DISPLAY INVISIBLE (-4500 3550);
FORCEPROP 1 LAST PART_NUMBER DFHST8FS479
J 0
(-5100 4800);
DISPLAY 0.468085 (-5100 4800);
PAINT SKYBLUE (-5100 4800);
DISPLAY INVISIBLE (-5100 4800);
FORCEADD GND..1
(-2925 5525);
FORCEPROP 3 LASTPIN (-2925 5575) SIG_NAME GND\g
J 0
(-2915 5585);
DISPLAY 0.659574 (-2915 5585);
PAINT MONO (-2915 5585);
DISPLAY INVISIBLE (-2915 5585);
FORCEPROP 2 LAST CDS_LIB pure_quanta_power
J 0
(-2925 5525);
DISPLAY INVISIBLE (-2925 5525);
FORCEPROP 2 LAST BOM_COST MEM
J 0
(-2900 5650);
DISPLAY 0.659574 (-2900 5650);
DISPLAY INVISIBLE (-2900 5650);
FORCEPROP 1 LAST SIZE 1B
J 0
(-2850 5475);
DISPLAY 0.723404 (-2850 5475);
PAINT GREEN (-2850 5475);
DISPLAY INVISIBLE (-2850 5475);
FORCEPROP 2 LAST ROOM MEM_EFGH_DECOUPLING_CAPS
J 0
(-2900 5600);
DISPLAY 0.659574 (-2900 5600);
PAINT RED (-2900 5600);
DISPLAY INVISIBLE (-2900 5600);
FORCEPROP 1 LAST HDL_POWER GND
J 0
(-2925 5675);
DISPLAY 0.723404 (-2925 5675);
PAINT GREEN (-2925 5675);
DISPLAY INVISIBLE (-2925 5675);
FORCEPROP 1 LAST PATH I237
J 0
(-2850 5525);
DISPLAY 0.872340 (-2850 5525);
PAINT AQUA (-2850 5525);
DISPLAY INVISIBLE (-2850 5525);
FORCEADD Q_CAP..1
R 2
(-2925 5875);
FORCEPROP 1 LAST LOCATION C178
J 2
(-2975 5975);
DISPLAY 0.489362 (-2975 5975);
PAINT SKYBLUE (-2975 5975);
FORCEPROP 0 LAST $SEC 1
J 0
(-2975 6025);
DISPLAY 0.680851 (-2975 6025);
PAINT MONO (-2975 6025);
DISPLAY INVISIBLE (-2975 6025);
FORCEPROP 0 LAST CDS_SEC 1
J 0
(-2975 6025);
DISPLAY 0.680851 (-2975 6025);
DISPLAY INVISIBLE (-2975 6025);
FORCEPROP 1 LASTPIN (-2925 5975) $PN 1
J 2
(-2935 5955);
DISPLAY 0.489362 (-2935 5955);
PAINT MONO (-2935 5955);
FORCEPROP 1 LASTPIN (-2925 5775) $PN 2
J 2
(-2935 5755);
DISPLAY 0.489362 (-2935 5755);
PAINT MONO (-2935 5755);
FORCEPROP 1 LAST VOLTAGE 25V
J 2
(-2975 5875);
DISPLAY 0.489362 (-2975 5875);
PAINT SKYBLUE (-2975 5875);
FORCEPROP 1 LAST TOLERANCE 10%
J 2
(-2975 5825);
DISPLAY 0.489362 (-2975 5825);
PAINT SKYBLUE (-2975 5825);
FORCEPROP 1 LAST PACK_TYPE C0805
J 2
(-2975 5675);
DISPLAY 0.489362 (-2975 5675);
PAINT SKYBLUE (-2975 5675);
FORCEPROP 1 LAST VALUE 10UF
J 2
(-2975 5925);
DISPLAY 0.489362 (-2975 5925);
PAINT SKYBLUE (-2975 5925);
FORCEPROP 1 LAST MATERIAL X6S
J 2
(-2975 5775);
DISPLAY 0.489362 (-2975 5775);
PAINT SKYBLUE (-2975 5775);
FORCEPROP 2 LAST CDS_LIB pure_quanta
J 0
(-2925 5875);
DISPLAY INVISIBLE (-2925 5875);
FORCEPROP 0 LAST BOM_COST MEM
J 2
(-2980 6020);
DISPLAY 0.595745 (-2980 6020);
PAINT MONO (-2980 6020);
DISPLAY INVISIBLE (-2980 6020);
FORCEPROP 2 LAST ROOM 
J 2
(-2980 6020);
DISPLAY 0.595745 (-2980 6020);
PAINT RED (-2980 6020);
DISPLAY INVISIBLE (-2980 6020);
FORCEPROP 1 LAST PATH I238
J 2
(-2975 6025);
DISPLAY 0.978723 (-2975 6025);
PAINT WHITE (-2975 6025);
DISPLAY INVISIBLE (-2975 6025);
FORCEPROP 1 LAST PART_NUMBER CH6104KEA00
J 2
(-2975 5725);
DISPLAY 0.489362 (-2975 5725);
PAINT SKYBLUE (-2975 5725);
DISPLAY INVISIBLE (-2975 5725);
FORCEADD Q_CAP..1
R 2
(-2350 5875);
FORCEPROP 1 LAST LOCATION C179
J 2
(-2400 5975);
DISPLAY 0.489362 (-2400 5975);
PAINT SKYBLUE (-2400 5975);
FORCEPROP 0 LAST $SEC 1
J 0
(-2400 6025);
DISPLAY 0.680851 (-2400 6025);
PAINT MONO (-2400 6025);
DISPLAY INVISIBLE (-2400 6025);
FORCEPROP 0 LAST CDS_SEC 1
J 0
(-2400 6025);
DISPLAY 0.680851 (-2400 6025);
DISPLAY INVISIBLE (-2400 6025);
FORCEPROP 1 LASTPIN (-2350 5975) $PN 1
J 2
(-2360 5955);
DISPLAY 0.489362 (-2360 5955);
PAINT MONO (-2360 5955);
FORCEPROP 1 LASTPIN (-2350 5775) $PN 2
J 2
(-2360 5755);
DISPLAY 0.489362 (-2360 5755);
PAINT MONO (-2360 5755);
FORCEPROP 1 LAST MATERIAL X6S
J 2
(-2400 5775);
DISPLAY 0.489362 (-2400 5775);
PAINT SKYBLUE (-2400 5775);
FORCEPROP 1 LAST PACK_TYPE C0805
J 2
(-2400 5675);
DISPLAY 0.489362 (-2400 5675);
PAINT SKYBLUE (-2400 5675);
FORCEPROP 1 LAST VOLTAGE 25V
J 2
(-2400 5875);
DISPLAY 0.489362 (-2400 5875);
PAINT SKYBLUE (-2400 5875);
FORCEPROP 1 LAST VALUE 10UF
J 2
(-2400 5925);
DISPLAY 0.489362 (-2400 5925);
PAINT SKYBLUE (-2400 5925);
FORCEPROP 1 LAST TOLERANCE 10%
J 2
(-2400 5825);
DISPLAY 0.489362 (-2400 5825);
PAINT SKYBLUE (-2400 5825);
FORCEPROP 2 LAST CDS_LIB pure_quanta
J 0
(-2350 5875);
DISPLAY INVISIBLE (-2350 5875);
FORCEPROP 0 LAST BOM_COST MEM
J 2
(-2405 6020);
DISPLAY 0.595745 (-2405 6020);
PAINT MONO (-2405 6020);
DISPLAY INVISIBLE (-2405 6020);
FORCEPROP 2 LAST ROOM 
J 2
(-2405 6020);
DISPLAY 0.595745 (-2405 6020);
PAINT RED (-2405 6020);
DISPLAY INVISIBLE (-2405 6020);
FORCEPROP 1 LAST PATH I239
J 2
(-2400 6025);
DISPLAY 0.978723 (-2400 6025);
PAINT WHITE (-2400 6025);
DISPLAY INVISIBLE (-2400 6025);
FORCEPROP 1 LAST PART_NUMBER CH6104KEA00
J 2
(-2400 5725);
DISPLAY 0.489362 (-2400 5725);
PAINT SKYBLUE (-2400 5725);
DISPLAY INVISIBLE (-2400 5725);
FORCEADD TAP..1
R 2
(-7900 3300);
FORCEPROP 3 LASTPIN (-7850 3300) SIG_NAME M_C_CPU1_SB_CB<2>
J 0
(-7840 3310);
DISPLAY 0.659574 (-7840 3310);
PAINT MONO (-7840 3310);
DISPLAY INVISIBLE (-7840 3310);
FORCEPROP 1 LASTPIN (-7850 3300) BN 2
J 2
(-7838 3308);
DISPLAY 0.489362 (-7838 3308);
PAINT GREEN (-7838 3308);
FORCEPROP 2 LAST CDS_LIB mstr_standard
J 0
(-7900 3300);
DISPLAY 0.723404 (-7900 3300);
PAINT MONO (-7900 3300);
DISPLAY INVISIBLE (-7900 3300);
FORCEPROP 1 LAST BODY_TYPE PLUMBING
J 2
(-7900 3350);
DISPLAY 0.872340 (-7900 3350);
PAINT GREEN (-7900 3350);
DISPLAY INVISIBLE (-7900 3350);
FORCEPROP 1 LAST HDL_TAP TRUE
J 2
(-8225 3175);
DISPLAY 0.872340 (-8225 3175);
DISPLAY INVISIBLE (-8225 3175);
FORCEPROP 1 LAST PATH I24
J 2
(-7898 3300);
DISPLAY 0.872340 (-7898 3300);
PAINT GREEN (-7898 3300);
DISPLAY INVISIBLE (-7898 3300);
FORCEADD UNIVERSAL_POWER..1
(-2925 6200);
FORCEPROP 3 LASTPIN (-2925 6150) SIG_NAME P12V_MEM_CPU1\g
J 0
(-2915 6160);
DISPLAY 0.659574 (-2915 6160);
PAINT MONO (-2915 6160);
DISPLAY INVISIBLE (-2915 6160);
FORCEPROP 1 LAST HDL_POWER P12V_MEM_CPU1
J 1
(-2925 6250);
DISPLAY 0.489362 (-2925 6250);
PAINT GREEN (-2925 6250);
FORCEPROP 2 LAST CDS_LIB pure_quanta_power
J 0
(-2925 6200);
DISPLAY INVISIBLE (-2925 6200);
FORCEPROP 1 LAST PATH I240
J 0
(-2875 6225);
DISPLAY 0.872340 (-2875 6225);
PAINT AQUA (-2875 6225);
DISPLAY INVISIBLE (-2875 6225);
FORCEADD OFFPAGE..1
(-8625 2625);
FORCEPROP 2 LAST $XR5 103 
J 0
(-9417 2625);
DISPLAY 0.638298 (-9417 2625);
PAINT MONO (-9417 2625);
FORCEPROP 2 LAST $XR4 102 
J 0
(-9297 2625);
DISPLAY 0.638298 (-9297 2625);
PAINT MONO (-9297 2625);
FORCEPROP 2 LAST $XR3 101 
J 0
(-9177 2625);
DISPLAY 0.638298 (-9177 2625);
PAINT MONO (-9177 2625);
FORCEPROP 2 LAST $XR2 99 
J 0
(-9057 2625);
DISPLAY 0.638298 (-9057 2625);
PAINT MONO (-9057 2625);
FORCEPROP 2 LAST $XR1 98 
J 0
(-8967 2625);
DISPLAY 0.638298 (-8967 2625);
PAINT MONO (-8967 2625);
FORCEPROP 2 LAST $XR0 159 
J 0
(-8877 2625);
DISPLAY 0.638298 (-8877 2625);
PAINT MONO (-8877 2625);
FORCEPROP 2 LAST CDS_LIB mstr_standard
J 0
(-8625 2625);
DISPLAY 0.808511 (-8625 2625);
DISPLAY INVISIBLE (-8625 2625);
FORCEPROP 1 LAST OFFPAGE TRUE
J 0
(-8300 2500);
DISPLAY 0.872340 (-8300 2500);
PAINT GREEN (-8300 2500);
DISPLAY INVISIBLE (-8300 2500);
FORCEPROP 1 LAST COMMENT_BODY TRUE
J 0
(-8500 2525);
DISPLAY 0.872340 (-8500 2525);
PAINT GREEN (-8500 2525);
DISPLAY INVISIBLE (-8500 2525);
FORCEPROP 2 LAST PATH I241
J 0
(-8925 2675);
DISPLAY 0.680851 (-8925 2675);
DISPLAY INVISIBLE (-8925 2675);
FORCEADD Q_RES..1
(-7925 2625);
FORCEPROP 1 LAST LOCATION R1582
J 0
(-7975 2650);
DISPLAY 0.510638 (-7975 2650);
PAINT SKYBLUE (-7975 2650);
FORCEPROP 0 LAST $SEC 1
J 0
(-7975 2725);
DISPLAY 0.680851 (-7975 2725);
PAINT MONO (-7975 2725);
DISPLAY INVISIBLE (-7975 2725);
FORCEPROP 0 LAST CDS_SEC 1
J 0
(-7975 2725);
DISPLAY 0.680851 (-7975 2725);
DISPLAY INVISIBLE (-7975 2725);
FORCEPROP 1 LASTPIN (-8025 2625) $PN 1
J 0
(-8013 2637);
DISPLAY 0.787234 (-8013 2637);
PAINT MONO (-8013 2637);
FORCEPROP 1 LASTPIN (-7825 2625) $PN 2
J 0
(-7863 2637);
DISPLAY 0.787234 (-7863 2637);
PAINT MONO (-7863 2637);
FORCEPROP 1 LAST VALUE 49.9
J 2
(-7775 2700);
DISPLAY 0.510638 (-7775 2700);
PAINT SKYBLUE (-7775 2700);
FORCEPROP 1 LAST MATERIAL CHIP
J 0
(-7925 2475);
DISPLAY 0.978723 (-7925 2475);
DISPLAY INVISIBLE (-7925 2475);
FORCEPROP 1 LAST PACK_TYPE 0402LF
J 0
(-7675 2475);
DISPLAY 0.978723 (-7675 2475);
DISPLAY INVISIBLE (-7675 2475);
FORCEPROP 1 LAST WATTAGE 1/16W
J 2
(-7950 2475);
DISPLAY 0.978723 (-7950 2475);
DISPLAY INVISIBLE (-7950 2475);
FORCEPROP 1 LAST TOLERANCE 1%
J 0
(-7925 2525);
DISPLAY 0.978723 (-7925 2525);
DISPLAY INVISIBLE (-7925 2525);
FORCEPROP 2 LAST CDS_LIB pure_quanta
J 0
(-7925 2625);
DISPLAY INVISIBLE (-7925 2625);
FORCEPROP 1 LAST PATH I242
J 0
(-7975 2775);
DISPLAY 0.978723 (-7975 2775);
PAINT WHITE (-7975 2775);
DISPLAY INVISIBLE (-7975 2775);
FORCEPROP 1 LAST PART_NUMBER CS04992FB07
J 0
(-7975 2725);
DISPLAY 0.978723 (-7975 2725);
DISPLAY INVISIBLE (-7975 2725);
FORCEADD Q_RES..1
(-8300 2850);
FORCEPROP 1 LAST LOCATION R1697
J 0
(-8475 2850);
DISPLAY 0.638298 (-8475 2850);
FORCEPROP 0 LAST $SEC 1
J 0
(-8475 2900);
DISPLAY 0.680851 (-8475 2900);
PAINT MONO (-8475 2900);
DISPLAY INVISIBLE (-8475 2900);
FORCEPROP 0 LAST CDS_SEC 1
J 0
(-8475 2900);
DISPLAY 0.680851 (-8475 2900);
DISPLAY INVISIBLE (-8475 2900);
FORCEPROP 1 LASTPIN (-8400 2850) $PN 1
J 0
(-8388 2862);
DISPLAY 0.787234 (-8388 2862);
PAINT MONO (-8388 2862);
FORCEPROP 1 LASTPIN (-8200 2850) $PN 2
J 0
(-8238 2862);
DISPLAY 0.787234 (-8238 2862);
PAINT MONO (-8238 2862);
FORCEPROP 1 LAST VALUE 10
J 2
(-8150 2850);
DISPLAY 0.404255 (-8150 2850);
FORCEPROP 1 LAST PACK_TYPE 0402LF
J 0
(-8250 2825);
DISPLAY 0.404255 (-8250 2825);
FORCEPROP 1 LAST MATERIAL CHIP
J 0
(-8400 2825);
DISPLAY 0.404255 (-8400 2825);
FORCEPROP 2 LAST CDS_LIB pure_quanta
J 0
(-8300 2850);
DISPLAY INVISIBLE (-8300 2850);
FORCEPROP 1 LAST WATTAGE 1/16W
J 2
(-8325 2700);
DISPLAY 0.978723 (-8325 2700);
DISPLAY INVISIBLE (-8325 2700);
FORCEPROP 1 LAST TOLERANCE 1%
J 0
(-8300 2750);
DISPLAY 0.978723 (-8300 2750);
DISPLAY INVISIBLE (-8300 2750);
FORCEPROP 1 LAST PATH I243
J 0
(-8350 3000);
DISPLAY 0.978723 (-8350 3000);
PAINT WHITE (-8350 3000);
DISPLAY INVISIBLE (-8350 3000);
FORCEPROP 1 LAST PART_NUMBER CS01002FB07
J 0
(-8350 2950);
DISPLAY 0.978723 (-8350 2950);
DISPLAY INVISIBLE (-8350 2950);
FORCEADD OFFPAGE..6
(-8975 2750);
FORCEPROP 2 LAST $XR5 159 
J 0
(-9314 2786);
DISPLAY 0.638298 (-9314 2786);
PAINT MONO (-9314 2786);
FORCEPROP 2 LAST $XR4 103 
J 0
(-9434 2714);
DISPLAY 0.638298 (-9434 2714);
PAINT MONO (-9434 2714);
FORCEPROP 2 LAST $XR3 102 
J 0
(-9314 2714);
DISPLAY 0.638298 (-9314 2714);
PAINT MONO (-9314 2714);
FORCEPROP 2 LAST $XR2 101 
J 0
(-9434 2750);
DISPLAY 0.638298 (-9434 2750);
PAINT MONO (-9434 2750);
FORCEPROP 2 LAST $XR1 99 
J 0
(-9314 2750);
DISPLAY 0.638298 (-9314 2750);
PAINT MONO (-9314 2750);
FORCEPROP 2 LAST $XR0 98 
J 0
(-9224 2750);
DISPLAY 0.638298 (-9224 2750);
PAINT MONO (-9224 2750);
FORCEPROP 2 LAST CDS_LIB mstr_standard
J 0
(-8975 2750);
DISPLAY 0.808511 (-8975 2750);
DISPLAY INVISIBLE (-8975 2750);
FORCEPROP 1 LAST OFFPAGE TRUE
J 0
(-8650 2625);
DISPLAY 0.872340 (-8650 2625);
PAINT GREEN (-8650 2625);
DISPLAY INVISIBLE (-8650 2625);
FORCEPROP 1 LAST COMMENT_BODY TRUE
J 0
(-8875 2675);
DISPLAY 0.872340 (-8875 2675);
PAINT GREEN (-8875 2675);
DISPLAY INVISIBLE (-8875 2675);
FORCEPROP 2 LAST PATH I244
J 0
(-9250 2800);
DISPLAY 0.680851 (-9250 2800);
DISPLAY INVISIBLE (-9250 2800);
FORCEADD TAP..1
R 2
(-7900 3250);
FORCEPROP 3 LASTPIN (-7850 3250) SIG_NAME M_C_CPU1_SB_CB<1>
J 0
(-7840 3260);
DISPLAY 0.659574 (-7840 3260);
PAINT MONO (-7840 3260);
DISPLAY INVISIBLE (-7840 3260);
FORCEPROP 1 LASTPIN (-7850 3250) BN 1
J 2
(-7838 3258);
DISPLAY 0.489362 (-7838 3258);
PAINT GREEN (-7838 3258);
FORCEPROP 2 LAST CDS_LIB mstr_standard
J 0
(-7900 3250);
DISPLAY 0.723404 (-7900 3250);
PAINT MONO (-7900 3250);
DISPLAY INVISIBLE (-7900 3250);
FORCEPROP 1 LAST BODY_TYPE PLUMBING
J 2
(-7900 3300);
DISPLAY 0.872340 (-7900 3300);
PAINT GREEN (-7900 3300);
DISPLAY INVISIBLE (-7900 3300);
FORCEPROP 1 LAST HDL_TAP TRUE
J 2
(-8225 3125);
DISPLAY 0.872340 (-8225 3125);
DISPLAY INVISIBLE (-8225 3125);
FORCEPROP 1 LAST PATH I25
J 2
(-7898 3250);
DISPLAY 0.872340 (-7898 3250);
PAINT GREEN (-7898 3250);
DISPLAY INVISIBLE (-7898 3250);
FORCEADD TAP..1
R 2
(-7900 3350);
FORCEPROP 3 LASTPIN (-7850 3350) SIG_NAME M_C_CPU1_SB_CB<3>
J 0
(-7840 3360);
DISPLAY 0.659574 (-7840 3360);
PAINT MONO (-7840 3360);
DISPLAY INVISIBLE (-7840 3360);
FORCEPROP 1 LASTPIN (-7850 3350) BN 3
J 2
(-7838 3358);
DISPLAY 0.489362 (-7838 3358);
PAINT GREEN (-7838 3358);
FORCEPROP 2 LAST CDS_LIB mstr_standard
J 0
(-7900 3350);
DISPLAY 0.723404 (-7900 3350);
PAINT MONO (-7900 3350);
DISPLAY INVISIBLE (-7900 3350);
FORCEPROP 1 LAST BODY_TYPE PLUMBING
J 2
(-7900 3400);
DISPLAY 0.872340 (-7900 3400);
PAINT GREEN (-7900 3400);
DISPLAY INVISIBLE (-7900 3400);
FORCEPROP 1 LAST HDL_TAP TRUE
J 2
(-8225 3225);
DISPLAY 0.872340 (-8225 3225);
DISPLAY INVISIBLE (-8225 3225);
FORCEPROP 1 LAST PATH I26
J 2
(-7898 3350);
DISPLAY 0.872340 (-7898 3350);
PAINT GREEN (-7898 3350);
DISPLAY INVISIBLE (-7898 3350);
FORCEADD TAP..1
R 2
(-7900 3400);
FORCEPROP 3 LASTPIN (-7850 3400) SIG_NAME M_C_CPU1_SB_CB<4>
J 0
(-7840 3410);
DISPLAY 0.659574 (-7840 3410);
PAINT MONO (-7840 3410);
DISPLAY INVISIBLE (-7840 3410);
FORCEPROP 1 LASTPIN (-7850 3400) BN 4
J 2
(-7838 3408);
DISPLAY 0.489362 (-7838 3408);
PAINT GREEN (-7838 3408);
FORCEPROP 2 LAST CDS_LIB mstr_standard
J 0
(-7900 3400);
DISPLAY 0.723404 (-7900 3400);
PAINT MONO (-7900 3400);
DISPLAY INVISIBLE (-7900 3400);
FORCEPROP 1 LAST BODY_TYPE PLUMBING
J 2
(-7900 3450);
DISPLAY 0.872340 (-7900 3450);
PAINT GREEN (-7900 3450);
DISPLAY INVISIBLE (-7900 3450);
FORCEPROP 1 LAST HDL_TAP TRUE
J 2
(-8225 3275);
DISPLAY 0.872340 (-8225 3275);
DISPLAY INVISIBLE (-8225 3275);
FORCEPROP 1 LAST PATH I27
J 2
(-7898 3400);
DISPLAY 0.872340 (-7898 3400);
PAINT GREEN (-7898 3400);
DISPLAY INVISIBLE (-7898 3400);
FORCEADD TAP..1
R 2
(-7900 3450);
FORCEPROP 3 LASTPIN (-7850 3450) SIG_NAME M_C_CPU1_SB_CB<5>
J 0
(-7840 3460);
DISPLAY 0.659574 (-7840 3460);
PAINT MONO (-7840 3460);
DISPLAY INVISIBLE (-7840 3460);
FORCEPROP 1 LASTPIN (-7850 3450) BN 5
J 2
(-7838 3458);
DISPLAY 0.489362 (-7838 3458);
PAINT GREEN (-7838 3458);
FORCEPROP 2 LAST CDS_LIB mstr_standard
J 0
(-7900 3450);
DISPLAY 0.723404 (-7900 3450);
PAINT MONO (-7900 3450);
DISPLAY INVISIBLE (-7900 3450);
FORCEPROP 1 LAST BODY_TYPE PLUMBING
J 2
(-7900 3500);
DISPLAY 0.872340 (-7900 3500);
PAINT GREEN (-7900 3500);
DISPLAY INVISIBLE (-7900 3500);
FORCEPROP 1 LAST HDL_TAP TRUE
J 2
(-8225 3325);
DISPLAY 0.872340 (-8225 3325);
DISPLAY INVISIBLE (-8225 3325);
FORCEPROP 1 LAST PATH I28
J 2
(-7898 3450);
DISPLAY 0.872340 (-7898 3450);
PAINT GREEN (-7898 3450);
DISPLAY INVISIBLE (-7898 3450);
FORCEADD TAP..1
R 2
(-7900 3550);
FORCEPROP 3 LASTPIN (-7850 3550) SIG_NAME M_C_CPU1_SB_CB<7>
J 0
(-7840 3560);
DISPLAY 0.659574 (-7840 3560);
PAINT MONO (-7840 3560);
DISPLAY INVISIBLE (-7840 3560);
FORCEPROP 1 LASTPIN (-7850 3550) BN 7
J 2
(-7838 3558);
DISPLAY 0.489362 (-7838 3558);
PAINT GREEN (-7838 3558);
FORCEPROP 2 LAST CDS_LIB mstr_standard
J 0
(-7900 3550);
DISPLAY 0.723404 (-7900 3550);
PAINT MONO (-7900 3550);
DISPLAY INVISIBLE (-7900 3550);
FORCEPROP 1 LAST BODY_TYPE PLUMBING
J 2
(-7900 3600);
DISPLAY 0.872340 (-7900 3600);
PAINT GREEN (-7900 3600);
DISPLAY INVISIBLE (-7900 3600);
FORCEPROP 1 LAST HDL_TAP TRUE
J 2
(-8225 3425);
DISPLAY 0.872340 (-8225 3425);
DISPLAY INVISIBLE (-8225 3425);
FORCEPROP 1 LAST PATH I29
J 2
(-7898 3550);
DISPLAY 0.872340 (-7898 3550);
PAINT GREEN (-7898 3550);
DISPLAY INVISIBLE (-7898 3550);
FORCEADD TAP..1
R 2
(-7900 3500);
FORCEPROP 3 LASTPIN (-7850 3500) SIG_NAME M_C_CPU1_SB_CB<6>
J 0
(-7840 3510);
DISPLAY 0.659574 (-7840 3510);
PAINT MONO (-7840 3510);
DISPLAY INVISIBLE (-7840 3510);
FORCEPROP 1 LASTPIN (-7850 3500) BN 6
J 2
(-7838 3508);
DISPLAY 0.489362 (-7838 3508);
PAINT GREEN (-7838 3508);
FORCEPROP 2 LAST CDS_LIB mstr_standard
J 0
(-7900 3500);
DISPLAY 0.723404 (-7900 3500);
PAINT MONO (-7900 3500);
DISPLAY INVISIBLE (-7900 3500);
FORCEPROP 1 LAST BODY_TYPE PLUMBING
J 2
(-7900 3550);
DISPLAY 0.872340 (-7900 3550);
PAINT GREEN (-7900 3550);
DISPLAY INVISIBLE (-7900 3550);
FORCEPROP 1 LAST HDL_TAP TRUE
J 2
(-8225 3375);
DISPLAY 0.872340 (-8225 3375);
DISPLAY INVISIBLE (-8225 3375);
FORCEPROP 1 LAST PATH I30
J 2
(-7898 3500);
DISPLAY 0.872340 (-7898 3500);
PAINT GREEN (-7898 3500);
DISPLAY INVISIBLE (-7898 3500);
FORCEADD TAP..1
R 2
(-7900 3650);
FORCEPROP 3 LASTPIN (-7850 3650) SIG_NAME M_C_CPU1_SA_CB<0>
J 0
(-7840 3660);
DISPLAY 0.659574 (-7840 3660);
PAINT MONO (-7840 3660);
DISPLAY INVISIBLE (-7840 3660);
FORCEPROP 1 LASTPIN (-7850 3650) BN 0
J 2
(-7838 3658);
DISPLAY 0.489362 (-7838 3658);
PAINT GREEN (-7838 3658);
FORCEPROP 2 LAST CDS_LIB mstr_standard
J 0
(-7900 3650);
DISPLAY 0.723404 (-7900 3650);
PAINT MONO (-7900 3650);
DISPLAY INVISIBLE (-7900 3650);
FORCEPROP 1 LAST BODY_TYPE PLUMBING
J 2
(-7900 3700);
DISPLAY 0.872340 (-7900 3700);
PAINT GREEN (-7900 3700);
DISPLAY INVISIBLE (-7900 3700);
FORCEPROP 1 LAST HDL_TAP TRUE
J 2
(-8225 3525);
DISPLAY 0.872340 (-8225 3525);
DISPLAY INVISIBLE (-8225 3525);
FORCEPROP 1 LAST PATH I31
J 2
(-7898 3650);
DISPLAY 0.872340 (-7898 3650);
PAINT GREEN (-7898 3650);
DISPLAY INVISIBLE (-7898 3650);
FORCEADD TAP..1
R 2
(-7900 3700);
FORCEPROP 3 LASTPIN (-7850 3700) SIG_NAME M_C_CPU1_SA_CB<1>
J 0
(-7840 3710);
DISPLAY 0.659574 (-7840 3710);
PAINT MONO (-7840 3710);
DISPLAY INVISIBLE (-7840 3710);
FORCEPROP 1 LASTPIN (-7850 3700) BN 1
J 2
(-7838 3708);
DISPLAY 0.489362 (-7838 3708);
PAINT GREEN (-7838 3708);
FORCEPROP 2 LAST CDS_LIB mstr_standard
J 0
(-7900 3700);
DISPLAY 0.723404 (-7900 3700);
PAINT MONO (-7900 3700);
DISPLAY INVISIBLE (-7900 3700);
FORCEPROP 1 LAST BODY_TYPE PLUMBING
J 2
(-7900 3750);
DISPLAY 0.872340 (-7900 3750);
PAINT GREEN (-7900 3750);
DISPLAY INVISIBLE (-7900 3750);
FORCEPROP 1 LAST HDL_TAP TRUE
J 2
(-8225 3575);
DISPLAY 0.872340 (-8225 3575);
DISPLAY INVISIBLE (-8225 3575);
FORCEPROP 1 LAST PATH I32
J 2
(-7898 3700);
DISPLAY 0.872340 (-7898 3700);
PAINT GREEN (-7898 3700);
DISPLAY INVISIBLE (-7898 3700);
FORCEADD TAP..1
R 2
(-7900 3750);
FORCEPROP 3 LASTPIN (-7850 3750) SIG_NAME M_C_CPU1_SA_CB<2>
J 0
(-7840 3760);
DISPLAY 0.659574 (-7840 3760);
PAINT MONO (-7840 3760);
DISPLAY INVISIBLE (-7840 3760);
FORCEPROP 1 LASTPIN (-7850 3750) BN 2
J 2
(-7838 3758);
DISPLAY 0.489362 (-7838 3758);
PAINT GREEN (-7838 3758);
FORCEPROP 2 LAST CDS_LIB mstr_standard
J 0
(-7900 3750);
DISPLAY 0.723404 (-7900 3750);
PAINT MONO (-7900 3750);
DISPLAY INVISIBLE (-7900 3750);
FORCEPROP 1 LAST BODY_TYPE PLUMBING
J 2
(-7900 3800);
DISPLAY 0.872340 (-7900 3800);
PAINT GREEN (-7900 3800);
DISPLAY INVISIBLE (-7900 3800);
FORCEPROP 1 LAST HDL_TAP TRUE
J 2
(-8225 3625);
DISPLAY 0.872340 (-8225 3625);
DISPLAY INVISIBLE (-8225 3625);
FORCEPROP 1 LAST PATH I33
J 2
(-7898 3750);
DISPLAY 0.872340 (-7898 3750);
PAINT GREEN (-7898 3750);
DISPLAY INVISIBLE (-7898 3750);
FORCEADD TAP..1
R 2
(-7900 3800);
FORCEPROP 3 LASTPIN (-7850 3800) SIG_NAME M_C_CPU1_SA_CB<3>
J 0
(-7840 3810);
DISPLAY 0.659574 (-7840 3810);
PAINT MONO (-7840 3810);
DISPLAY INVISIBLE (-7840 3810);
FORCEPROP 1 LASTPIN (-7850 3800) BN 3
J 2
(-7838 3808);
DISPLAY 0.489362 (-7838 3808);
PAINT GREEN (-7838 3808);
FORCEPROP 2 LAST CDS_LIB mstr_standard
J 0
(-7900 3800);
DISPLAY 0.723404 (-7900 3800);
PAINT MONO (-7900 3800);
DISPLAY INVISIBLE (-7900 3800);
FORCEPROP 1 LAST BODY_TYPE PLUMBING
J 2
(-7900 3850);
DISPLAY 0.872340 (-7900 3850);
PAINT GREEN (-7900 3850);
DISPLAY INVISIBLE (-7900 3850);
FORCEPROP 1 LAST HDL_TAP TRUE
J 2
(-8225 3675);
DISPLAY 0.872340 (-8225 3675);
DISPLAY INVISIBLE (-8225 3675);
FORCEPROP 1 LAST PATH I34
J 2
(-7898 3800);
DISPLAY 0.872340 (-7898 3800);
PAINT GREEN (-7898 3800);
DISPLAY INVISIBLE (-7898 3800);
FORCEADD TAP..1
(-6200 2250);
FORCEPROP 3 LASTPIN (-6250 2250) SIG_NAME M_C_CPU1_SB_DQ<1>
J 0
(-6240 2260);
DISPLAY 0.659574 (-6240 2260);
PAINT MONO (-6240 2260);
DISPLAY INVISIBLE (-6240 2260);
FORCEPROP 1 LASTPIN (-6250 2250) BN 1
J 0
(-6262 2258);
DISPLAY 0.489362 (-6262 2258);
PAINT GREEN (-6262 2258);
FORCEPROP 2 LAST CDS_LIB mstr_standard
J 0
(-6200 2250);
DISPLAY 0.723404 (-6200 2250);
PAINT MONO (-6200 2250);
DISPLAY INVISIBLE (-6200 2250);
FORCEPROP 1 LAST BODY_TYPE PLUMBING
J 0
(-6200 2300);
DISPLAY 0.872340 (-6200 2300);
PAINT GREEN (-6200 2300);
DISPLAY INVISIBLE (-6200 2300);
FORCEPROP 1 LAST HDL_TAP TRUE
J 0
(-5875 2125);
DISPLAY 0.872340 (-5875 2125);
DISPLAY INVISIBLE (-5875 2125);
FORCEPROP 1 LAST PATH I35
J 0
(-6202 2250);
DISPLAY 0.872340 (-6202 2250);
PAINT GREEN (-6202 2250);
DISPLAY INVISIBLE (-6202 2250);
FORCEADD TAP..1
(-6200 2200);
FORCEPROP 3 LASTPIN (-6250 2200) SIG_NAME M_C_CPU1_SB_DQ<0>
J 0
(-6240 2210);
DISPLAY 0.659574 (-6240 2210);
PAINT MONO (-6240 2210);
DISPLAY INVISIBLE (-6240 2210);
FORCEPROP 1 LASTPIN (-6250 2200) BN 0
J 0
(-6262 2208);
DISPLAY 0.489362 (-6262 2208);
PAINT GREEN (-6262 2208);
FORCEPROP 2 LAST CDS_LIB mstr_standard
J 0
(-6200 2200);
DISPLAY 0.723404 (-6200 2200);
PAINT MONO (-6200 2200);
DISPLAY INVISIBLE (-6200 2200);
FORCEPROP 1 LAST BODY_TYPE PLUMBING
J 0
(-6200 2250);
DISPLAY 0.872340 (-6200 2250);
PAINT GREEN (-6200 2250);
DISPLAY INVISIBLE (-6200 2250);
FORCEPROP 1 LAST HDL_TAP TRUE
J 0
(-5875 2075);
DISPLAY 0.872340 (-5875 2075);
DISPLAY INVISIBLE (-5875 2075);
FORCEPROP 1 LAST PATH I36
J 0
(-6202 2200);
DISPLAY 0.872340 (-6202 2200);
PAINT GREEN (-6202 2200);
DISPLAY INVISIBLE (-6202 2200);
FORCEADD TAP..1
(-6200 2300);
FORCEPROP 3 LASTPIN (-6250 2300) SIG_NAME M_C_CPU1_SB_DQ<2>
J 0
(-6240 2310);
DISPLAY 0.659574 (-6240 2310);
PAINT MONO (-6240 2310);
DISPLAY INVISIBLE (-6240 2310);
FORCEPROP 1 LASTPIN (-6250 2300) BN 2
J 0
(-6262 2308);
DISPLAY 0.489362 (-6262 2308);
PAINT GREEN (-6262 2308);
FORCEPROP 2 LAST CDS_LIB mstr_standard
J 0
(-6200 2300);
DISPLAY 0.723404 (-6200 2300);
PAINT MONO (-6200 2300);
DISPLAY INVISIBLE (-6200 2300);
FORCEPROP 1 LAST BODY_TYPE PLUMBING
J 0
(-6200 2350);
DISPLAY 0.872340 (-6200 2350);
PAINT GREEN (-6200 2350);
DISPLAY INVISIBLE (-6200 2350);
FORCEPROP 1 LAST HDL_TAP TRUE
J 0
(-5875 2175);
DISPLAY 0.872340 (-5875 2175);
DISPLAY INVISIBLE (-5875 2175);
FORCEPROP 1 LAST PATH I37
J 0
(-6202 2300);
DISPLAY 0.872340 (-6202 2300);
PAINT GREEN (-6202 2300);
DISPLAY INVISIBLE (-6202 2300);
FORCEADD TAP..1
(-6200 2350);
FORCEPROP 3 LASTPIN (-6250 2350) SIG_NAME M_C_CPU1_SB_DQ<3>
J 0
(-6240 2360);
DISPLAY 0.659574 (-6240 2360);
PAINT MONO (-6240 2360);
DISPLAY INVISIBLE (-6240 2360);
FORCEPROP 1 LASTPIN (-6250 2350) BN 3
J 0
(-6262 2358);
DISPLAY 0.489362 (-6262 2358);
PAINT GREEN (-6262 2358);
FORCEPROP 2 LAST CDS_LIB mstr_standard
J 0
(-6200 2350);
DISPLAY 0.723404 (-6200 2350);
PAINT MONO (-6200 2350);
DISPLAY INVISIBLE (-6200 2350);
FORCEPROP 1 LAST BODY_TYPE PLUMBING
J 0
(-6200 2400);
DISPLAY 0.872340 (-6200 2400);
PAINT GREEN (-6200 2400);
DISPLAY INVISIBLE (-6200 2400);
FORCEPROP 1 LAST HDL_TAP TRUE
J 0
(-5875 2225);
DISPLAY 0.872340 (-5875 2225);
DISPLAY INVISIBLE (-5875 2225);
FORCEPROP 1 LAST PATH I38
J 0
(-6202 2350);
DISPLAY 0.872340 (-6202 2350);
PAINT GREEN (-6202 2350);
DISPLAY INVISIBLE (-6202 2350);
FORCEADD TAP..1
(-6200 2400);
FORCEPROP 3 LASTPIN (-6250 2400) SIG_NAME M_C_CPU1_SB_DQ<4>
J 0
(-6240 2410);
DISPLAY 0.659574 (-6240 2410);
PAINT MONO (-6240 2410);
DISPLAY INVISIBLE (-6240 2410);
FORCEPROP 1 LASTPIN (-6250 2400) BN 4
J 0
(-6262 2408);
DISPLAY 0.489362 (-6262 2408);
PAINT GREEN (-6262 2408);
FORCEPROP 2 LAST CDS_LIB mstr_standard
J 0
(-6200 2400);
DISPLAY 0.723404 (-6200 2400);
PAINT MONO (-6200 2400);
DISPLAY INVISIBLE (-6200 2400);
FORCEPROP 1 LAST BODY_TYPE PLUMBING
J 0
(-6200 2450);
DISPLAY 0.872340 (-6200 2450);
PAINT GREEN (-6200 2450);
DISPLAY INVISIBLE (-6200 2450);
FORCEPROP 1 LAST HDL_TAP TRUE
J 0
(-5875 2275);
DISPLAY 0.872340 (-5875 2275);
DISPLAY INVISIBLE (-5875 2275);
FORCEPROP 1 LAST PATH I39
J 0
(-6202 2400);
DISPLAY 0.872340 (-6202 2400);
PAINT GREEN (-6202 2400);
DISPLAY INVISIBLE (-6202 2400);
FORCEADD TAP..1
(-6200 2450);
FORCEPROP 3 LASTPIN (-6250 2450) SIG_NAME M_C_CPU1_SB_DQ<5>
J 0
(-6240 2460);
DISPLAY 0.659574 (-6240 2460);
PAINT MONO (-6240 2460);
DISPLAY INVISIBLE (-6240 2460);
FORCEPROP 1 LASTPIN (-6250 2450) BN 5
J 0
(-6262 2458);
DISPLAY 0.489362 (-6262 2458);
PAINT GREEN (-6262 2458);
FORCEPROP 2 LAST CDS_LIB mstr_standard
J 0
(-6200 2450);
DISPLAY 0.723404 (-6200 2450);
PAINT MONO (-6200 2450);
DISPLAY INVISIBLE (-6200 2450);
FORCEPROP 1 LAST BODY_TYPE PLUMBING
J 0
(-6200 2500);
DISPLAY 0.872340 (-6200 2500);
PAINT GREEN (-6200 2500);
DISPLAY INVISIBLE (-6200 2500);
FORCEPROP 1 LAST HDL_TAP TRUE
J 0
(-5875 2325);
DISPLAY 0.872340 (-5875 2325);
DISPLAY INVISIBLE (-5875 2325);
FORCEPROP 1 LAST PATH I40
J 0
(-6202 2450);
DISPLAY 0.872340 (-6202 2450);
PAINT GREEN (-6202 2450);
DISPLAY INVISIBLE (-6202 2450);
FORCEADD TAP..1
(-6200 2550);
FORCEPROP 3 LASTPIN (-6250 2550) SIG_NAME M_C_CPU1_SB_DQ<7>
J 0
(-6240 2560);
DISPLAY 0.659574 (-6240 2560);
PAINT MONO (-6240 2560);
DISPLAY INVISIBLE (-6240 2560);
FORCEPROP 1 LASTPIN (-6250 2550) BN 7
J 0
(-6262 2558);
DISPLAY 0.489362 (-6262 2558);
PAINT GREEN (-6262 2558);
FORCEPROP 2 LAST CDS_LIB mstr_standard
J 0
(-6200 2550);
DISPLAY 0.723404 (-6200 2550);
PAINT MONO (-6200 2550);
DISPLAY INVISIBLE (-6200 2550);
FORCEPROP 1 LAST BODY_TYPE PLUMBING
J 0
(-6200 2600);
DISPLAY 0.872340 (-6200 2600);
PAINT GREEN (-6200 2600);
DISPLAY INVISIBLE (-6200 2600);
FORCEPROP 1 LAST HDL_TAP TRUE
J 0
(-5875 2425);
DISPLAY 0.872340 (-5875 2425);
DISPLAY INVISIBLE (-5875 2425);
FORCEPROP 1 LAST PATH I41
J 0
(-6202 2550);
DISPLAY 0.872340 (-6202 2550);
PAINT GREEN (-6202 2550);
DISPLAY INVISIBLE (-6202 2550);
FORCEADD TAP..1
(-6200 2500);
FORCEPROP 3 LASTPIN (-6250 2500) SIG_NAME M_C_CPU1_SB_DQ<6>
J 0
(-6240 2510);
DISPLAY 0.659574 (-6240 2510);
PAINT MONO (-6240 2510);
DISPLAY INVISIBLE (-6240 2510);
FORCEPROP 1 LASTPIN (-6250 2500) BN 6
J 0
(-6262 2508);
DISPLAY 0.489362 (-6262 2508);
PAINT GREEN (-6262 2508);
FORCEPROP 2 LAST CDS_LIB mstr_standard
J 0
(-6200 2500);
DISPLAY 0.723404 (-6200 2500);
PAINT MONO (-6200 2500);
DISPLAY INVISIBLE (-6200 2500);
FORCEPROP 1 LAST BODY_TYPE PLUMBING
J 0
(-6200 2550);
DISPLAY 0.872340 (-6200 2550);
PAINT GREEN (-6200 2550);
DISPLAY INVISIBLE (-6200 2550);
FORCEPROP 1 LAST HDL_TAP TRUE
J 0
(-5875 2375);
DISPLAY 0.872340 (-5875 2375);
DISPLAY INVISIBLE (-5875 2375);
FORCEPROP 1 LAST PATH I42
J 0
(-6202 2500);
DISPLAY 0.872340 (-6202 2500);
PAINT GREEN (-6202 2500);
DISPLAY INVISIBLE (-6202 2500);
FORCEADD TAP..1
(-6200 2650);
FORCEPROP 3 LASTPIN (-6250 2650) SIG_NAME M_C_CPU1_SB_DQ<9>
J 0
(-6240 2660);
DISPLAY 0.659574 (-6240 2660);
PAINT MONO (-6240 2660);
DISPLAY INVISIBLE (-6240 2660);
FORCEPROP 1 LASTPIN (-6250 2650) BN 9
J 0
(-6262 2658);
DISPLAY 0.489362 (-6262 2658);
PAINT GREEN (-6262 2658);
FORCEPROP 2 LAST CDS_LIB mstr_standard
J 0
(-6200 2650);
DISPLAY 0.723404 (-6200 2650);
PAINT MONO (-6200 2650);
DISPLAY INVISIBLE (-6200 2650);
FORCEPROP 1 LAST BODY_TYPE PLUMBING
J 0
(-6200 2700);
DISPLAY 0.872340 (-6200 2700);
PAINT GREEN (-6200 2700);
DISPLAY INVISIBLE (-6200 2700);
FORCEPROP 1 LAST HDL_TAP TRUE
J 0
(-5875 2525);
DISPLAY 0.872340 (-5875 2525);
DISPLAY INVISIBLE (-5875 2525);
FORCEPROP 1 LAST PATH I43
J 0
(-6202 2650);
DISPLAY 0.872340 (-6202 2650);
PAINT GREEN (-6202 2650);
DISPLAY INVISIBLE (-6202 2650);
FORCEADD TAP..1
(-6200 2600);
FORCEPROP 3 LASTPIN (-6250 2600) SIG_NAME M_C_CPU1_SB_DQ<8>
J 0
(-6240 2610);
DISPLAY 0.659574 (-6240 2610);
PAINT MONO (-6240 2610);
DISPLAY INVISIBLE (-6240 2610);
FORCEPROP 1 LASTPIN (-6250 2600) BN 8
J 0
(-6262 2608);
DISPLAY 0.489362 (-6262 2608);
PAINT GREEN (-6262 2608);
FORCEPROP 2 LAST CDS_LIB mstr_standard
J 0
(-6200 2600);
DISPLAY 0.723404 (-6200 2600);
PAINT MONO (-6200 2600);
DISPLAY INVISIBLE (-6200 2600);
FORCEPROP 1 LAST BODY_TYPE PLUMBING
J 0
(-6200 2650);
DISPLAY 0.872340 (-6200 2650);
PAINT GREEN (-6200 2650);
DISPLAY INVISIBLE (-6200 2650);
FORCEPROP 1 LAST HDL_TAP TRUE
J 0
(-5875 2475);
DISPLAY 0.872340 (-5875 2475);
DISPLAY INVISIBLE (-5875 2475);
FORCEPROP 1 LAST PATH I44
J 0
(-6202 2600);
DISPLAY 0.872340 (-6202 2600);
PAINT GREEN (-6202 2600);
DISPLAY INVISIBLE (-6202 2600);
FORCEADD TAP..1
(-6200 2750);
FORCEPROP 3 LASTPIN (-6250 2750) SIG_NAME M_C_CPU1_SB_DQ<11>
J 0
(-6240 2760);
DISPLAY 0.659574 (-6240 2760);
PAINT MONO (-6240 2760);
DISPLAY INVISIBLE (-6240 2760);
FORCEPROP 1 LASTPIN (-6250 2750) BN 11
J 0
(-6262 2758);
DISPLAY 0.489362 (-6262 2758);
PAINT GREEN (-6262 2758);
FORCEPROP 2 LAST CDS_LIB mstr_standard
J 0
(-6200 2750);
DISPLAY 0.723404 (-6200 2750);
PAINT MONO (-6200 2750);
DISPLAY INVISIBLE (-6200 2750);
FORCEPROP 1 LAST BODY_TYPE PLUMBING
J 0
(-6200 2800);
DISPLAY 0.872340 (-6200 2800);
PAINT GREEN (-6200 2800);
DISPLAY INVISIBLE (-6200 2800);
FORCEPROP 1 LAST HDL_TAP TRUE
J 0
(-5875 2625);
DISPLAY 0.872340 (-5875 2625);
DISPLAY INVISIBLE (-5875 2625);
FORCEPROP 1 LAST PATH I45
J 0
(-6202 2750);
DISPLAY 0.872340 (-6202 2750);
PAINT GREEN (-6202 2750);
DISPLAY INVISIBLE (-6202 2750);
FORCEADD TAP..1
(-6200 2800);
FORCEPROP 3 LASTPIN (-6250 2800) SIG_NAME M_C_CPU1_SB_DQ<12>
J 0
(-6240 2810);
DISPLAY 0.659574 (-6240 2810);
PAINT MONO (-6240 2810);
DISPLAY INVISIBLE (-6240 2810);
FORCEPROP 1 LASTPIN (-6250 2800) BN 12
J 0
(-6262 2808);
DISPLAY 0.489362 (-6262 2808);
PAINT GREEN (-6262 2808);
FORCEPROP 2 LAST CDS_LIB mstr_standard
J 0
(-6200 2800);
DISPLAY 0.723404 (-6200 2800);
PAINT MONO (-6200 2800);
DISPLAY INVISIBLE (-6200 2800);
FORCEPROP 1 LAST BODY_TYPE PLUMBING
J 0
(-6200 2850);
DISPLAY 0.872340 (-6200 2850);
PAINT GREEN (-6200 2850);
DISPLAY INVISIBLE (-6200 2850);
FORCEPROP 1 LAST HDL_TAP TRUE
J 0
(-5875 2675);
DISPLAY 0.872340 (-5875 2675);
DISPLAY INVISIBLE (-5875 2675);
FORCEPROP 1 LAST PATH I46
J 0
(-6202 2800);
DISPLAY 0.872340 (-6202 2800);
PAINT GREEN (-6202 2800);
DISPLAY INVISIBLE (-6202 2800);
FORCEADD TAP..1
(-6200 2700);
FORCEPROP 3 LASTPIN (-6250 2700) SIG_NAME M_C_CPU1_SB_DQ<10>
J 0
(-6240 2710);
DISPLAY 0.659574 (-6240 2710);
PAINT MONO (-6240 2710);
DISPLAY INVISIBLE (-6240 2710);
FORCEPROP 1 LASTPIN (-6250 2700) BN 10
J 0
(-6262 2708);
DISPLAY 0.489362 (-6262 2708);
PAINT GREEN (-6262 2708);
FORCEPROP 2 LAST CDS_LIB mstr_standard
J 0
(-6200 2700);
DISPLAY 0.723404 (-6200 2700);
PAINT MONO (-6200 2700);
DISPLAY INVISIBLE (-6200 2700);
FORCEPROP 1 LAST BODY_TYPE PLUMBING
J 0
(-6200 2750);
DISPLAY 0.872340 (-6200 2750);
PAINT GREEN (-6200 2750);
DISPLAY INVISIBLE (-6200 2750);
FORCEPROP 1 LAST HDL_TAP TRUE
J 0
(-5875 2575);
DISPLAY 0.872340 (-5875 2575);
DISPLAY INVISIBLE (-5875 2575);
FORCEPROP 1 LAST PATH I47
J 0
(-6202 2700);
DISPLAY 0.872340 (-6202 2700);
PAINT GREEN (-6202 2700);
DISPLAY INVISIBLE (-6202 2700);
FORCEADD TAP..1
(-6200 2850);
FORCEPROP 3 LASTPIN (-6250 2850) SIG_NAME M_C_CPU1_SB_DQ<13>
J 0
(-6240 2860);
DISPLAY 0.659574 (-6240 2860);
PAINT MONO (-6240 2860);
DISPLAY INVISIBLE (-6240 2860);
FORCEPROP 1 LASTPIN (-6250 2850) BN 13
J 0
(-6262 2858);
DISPLAY 0.489362 (-6262 2858);
PAINT GREEN (-6262 2858);
FORCEPROP 2 LAST CDS_LIB mstr_standard
J 0
(-6200 2850);
DISPLAY 0.723404 (-6200 2850);
PAINT MONO (-6200 2850);
DISPLAY INVISIBLE (-6200 2850);
FORCEPROP 1 LAST BODY_TYPE PLUMBING
J 0
(-6200 2900);
DISPLAY 0.872340 (-6200 2900);
PAINT GREEN (-6200 2900);
DISPLAY INVISIBLE (-6200 2900);
FORCEPROP 1 LAST HDL_TAP TRUE
J 0
(-5875 2725);
DISPLAY 0.872340 (-5875 2725);
DISPLAY INVISIBLE (-5875 2725);
FORCEPROP 1 LAST PATH I48
J 0
(-6202 2850);
DISPLAY 0.872340 (-6202 2850);
PAINT GREEN (-6202 2850);
DISPLAY INVISIBLE (-6202 2850);
FORCEADD TAP..1
(-6200 2900);
FORCEPROP 3 LASTPIN (-6250 2900) SIG_NAME M_C_CPU1_SB_DQ<14>
J 0
(-6240 2910);
DISPLAY 0.659574 (-6240 2910);
PAINT MONO (-6240 2910);
DISPLAY INVISIBLE (-6240 2910);
FORCEPROP 1 LASTPIN (-6250 2900) BN 14
J 0
(-6262 2908);
DISPLAY 0.489362 (-6262 2908);
PAINT GREEN (-6262 2908);
FORCEPROP 2 LAST CDS_LIB mstr_standard
J 0
(-6200 2900);
DISPLAY 0.723404 (-6200 2900);
PAINT MONO (-6200 2900);
DISPLAY INVISIBLE (-6200 2900);
FORCEPROP 1 LAST BODY_TYPE PLUMBING
J 0
(-6200 2950);
DISPLAY 0.872340 (-6200 2950);
PAINT GREEN (-6200 2950);
DISPLAY INVISIBLE (-6200 2950);
FORCEPROP 1 LAST HDL_TAP TRUE
J 0
(-5875 2775);
DISPLAY 0.872340 (-5875 2775);
DISPLAY INVISIBLE (-5875 2775);
FORCEPROP 1 LAST PATH I49
J 0
(-6202 2900);
DISPLAY 0.872340 (-6202 2900);
PAINT GREEN (-6202 2900);
DISPLAY INVISIBLE (-6202 2900);
FORCEADD TAP..1
(-6200 2950);
FORCEPROP 3 LASTPIN (-6250 2950) SIG_NAME M_C_CPU1_SB_DQ<15>
J 0
(-6240 2960);
DISPLAY 0.659574 (-6240 2960);
PAINT MONO (-6240 2960);
DISPLAY INVISIBLE (-6240 2960);
FORCEPROP 1 LASTPIN (-6250 2950) BN 15
J 0
(-6262 2958);
DISPLAY 0.489362 (-6262 2958);
PAINT GREEN (-6262 2958);
FORCEPROP 2 LAST CDS_LIB mstr_standard
J 0
(-6200 2950);
DISPLAY 0.723404 (-6200 2950);
PAINT MONO (-6200 2950);
DISPLAY INVISIBLE (-6200 2950);
FORCEPROP 1 LAST BODY_TYPE PLUMBING
J 0
(-6200 3000);
DISPLAY 0.872340 (-6200 3000);
PAINT GREEN (-6200 3000);
DISPLAY INVISIBLE (-6200 3000);
FORCEPROP 1 LAST HDL_TAP TRUE
J 0
(-5875 2825);
DISPLAY 0.872340 (-5875 2825);
DISPLAY INVISIBLE (-5875 2825);
FORCEPROP 1 LAST PATH I50
J 0
(-6202 2950);
DISPLAY 0.872340 (-6202 2950);
PAINT GREEN (-6202 2950);
DISPLAY INVISIBLE (-6202 2950);
FORCEADD TAP..1
(-6200 3050);
FORCEPROP 3 LASTPIN (-6250 3050) SIG_NAME M_C_CPU1_SB_DQ<17>
J 0
(-6240 3060);
DISPLAY 0.659574 (-6240 3060);
PAINT MONO (-6240 3060);
DISPLAY INVISIBLE (-6240 3060);
FORCEPROP 1 LASTPIN (-6250 3050) BN 17
J 0
(-6262 3058);
DISPLAY 0.489362 (-6262 3058);
PAINT GREEN (-6262 3058);
FORCEPROP 2 LAST CDS_LIB mstr_standard
J 0
(-6200 3050);
DISPLAY 0.723404 (-6200 3050);
PAINT MONO (-6200 3050);
DISPLAY INVISIBLE (-6200 3050);
FORCEPROP 1 LAST BODY_TYPE PLUMBING
J 0
(-6200 3100);
DISPLAY 0.872340 (-6200 3100);
PAINT GREEN (-6200 3100);
DISPLAY INVISIBLE (-6200 3100);
FORCEPROP 1 LAST HDL_TAP TRUE
J 0
(-5875 2925);
DISPLAY 0.872340 (-5875 2925);
DISPLAY INVISIBLE (-5875 2925);
FORCEPROP 1 LAST PATH I51
J 0
(-6202 3050);
DISPLAY 0.872340 (-6202 3050);
PAINT GREEN (-6202 3050);
DISPLAY INVISIBLE (-6202 3050);
FORCEADD TAP..1
(-6200 3000);
FORCEPROP 3 LASTPIN (-6250 3000) SIG_NAME M_C_CPU1_SB_DQ<16>
J 0
(-6240 3010);
DISPLAY 0.659574 (-6240 3010);
PAINT MONO (-6240 3010);
DISPLAY INVISIBLE (-6240 3010);
FORCEPROP 1 LASTPIN (-6250 3000) BN 16
J 0
(-6262 3008);
DISPLAY 0.489362 (-6262 3008);
PAINT GREEN (-6262 3008);
FORCEPROP 2 LAST CDS_LIB mstr_standard
J 0
(-6200 3000);
DISPLAY 0.723404 (-6200 3000);
PAINT MONO (-6200 3000);
DISPLAY INVISIBLE (-6200 3000);
FORCEPROP 1 LAST BODY_TYPE PLUMBING
J 0
(-6200 3050);
DISPLAY 0.872340 (-6200 3050);
PAINT GREEN (-6200 3050);
DISPLAY INVISIBLE (-6200 3050);
FORCEPROP 1 LAST HDL_TAP TRUE
J 0
(-5875 2875);
DISPLAY 0.872340 (-5875 2875);
DISPLAY INVISIBLE (-5875 2875);
FORCEPROP 1 LAST PATH I52
J 0
(-6202 3000);
DISPLAY 0.872340 (-6202 3000);
PAINT GREEN (-6202 3000);
DISPLAY INVISIBLE (-6202 3000);
FORCEADD TAP..1
(-6200 3100);
FORCEPROP 3 LASTPIN (-6250 3100) SIG_NAME M_C_CPU1_SB_DQ<18>
J 0
(-6240 3110);
DISPLAY 0.659574 (-6240 3110);
PAINT MONO (-6240 3110);
DISPLAY INVISIBLE (-6240 3110);
FORCEPROP 1 LASTPIN (-6250 3100) BN 18
J 0
(-6262 3108);
DISPLAY 0.489362 (-6262 3108);
PAINT GREEN (-6262 3108);
FORCEPROP 2 LAST CDS_LIB mstr_standard
J 0
(-6200 3100);
DISPLAY 0.723404 (-6200 3100);
PAINT MONO (-6200 3100);
DISPLAY INVISIBLE (-6200 3100);
FORCEPROP 1 LAST BODY_TYPE PLUMBING
J 0
(-6200 3150);
DISPLAY 0.872340 (-6200 3150);
PAINT GREEN (-6200 3150);
DISPLAY INVISIBLE (-6200 3150);
FORCEPROP 1 LAST HDL_TAP TRUE
J 0
(-5875 2975);
DISPLAY 0.872340 (-5875 2975);
DISPLAY INVISIBLE (-5875 2975);
FORCEPROP 1 LAST PATH I53
J 0
(-6202 3100);
DISPLAY 0.872340 (-6202 3100);
PAINT GREEN (-6202 3100);
DISPLAY INVISIBLE (-6202 3100);
FORCEADD TAP..1
(-6200 3150);
FORCEPROP 3 LASTPIN (-6250 3150) SIG_NAME M_C_CPU1_SB_DQ<19>
J 0
(-6240 3160);
DISPLAY 0.659574 (-6240 3160);
PAINT MONO (-6240 3160);
DISPLAY INVISIBLE (-6240 3160);
FORCEPROP 1 LASTPIN (-6250 3150) BN 19
J 0
(-6262 3158);
DISPLAY 0.489362 (-6262 3158);
PAINT GREEN (-6262 3158);
FORCEPROP 2 LAST CDS_LIB mstr_standard
J 0
(-6200 3150);
DISPLAY 0.723404 (-6200 3150);
PAINT MONO (-6200 3150);
DISPLAY INVISIBLE (-6200 3150);
FORCEPROP 1 LAST BODY_TYPE PLUMBING
J 0
(-6200 3200);
DISPLAY 0.872340 (-6200 3200);
PAINT GREEN (-6200 3200);
DISPLAY INVISIBLE (-6200 3200);
FORCEPROP 1 LAST HDL_TAP TRUE
J 0
(-5875 3025);
DISPLAY 0.872340 (-5875 3025);
DISPLAY INVISIBLE (-5875 3025);
FORCEPROP 1 LAST PATH I54
J 0
(-6202 3150);
DISPLAY 0.872340 (-6202 3150);
PAINT GREEN (-6202 3150);
DISPLAY INVISIBLE (-6202 3150);
FORCEADD TAP..1
(-6200 3200);
FORCEPROP 3 LASTPIN (-6250 3200) SIG_NAME M_C_CPU1_SB_DQ<20>
J 0
(-6240 3210);
DISPLAY 0.659574 (-6240 3210);
PAINT MONO (-6240 3210);
DISPLAY INVISIBLE (-6240 3210);
FORCEPROP 1 LASTPIN (-6250 3200) BN 20
J 0
(-6262 3208);
DISPLAY 0.489362 (-6262 3208);
PAINT GREEN (-6262 3208);
FORCEPROP 2 LAST CDS_LIB mstr_standard
J 0
(-6200 3200);
DISPLAY 0.723404 (-6200 3200);
PAINT MONO (-6200 3200);
DISPLAY INVISIBLE (-6200 3200);
FORCEPROP 1 LAST BODY_TYPE PLUMBING
J 0
(-6200 3250);
DISPLAY 0.872340 (-6200 3250);
PAINT GREEN (-6200 3250);
DISPLAY INVISIBLE (-6200 3250);
FORCEPROP 1 LAST HDL_TAP TRUE
J 0
(-5875 3075);
DISPLAY 0.872340 (-5875 3075);
DISPLAY INVISIBLE (-5875 3075);
FORCEPROP 1 LAST PATH I55
J 0
(-6202 3200);
DISPLAY 0.872340 (-6202 3200);
PAINT GREEN (-6202 3200);
DISPLAY INVISIBLE (-6202 3200);
FORCEADD TAP..1
(-6200 3300);
FORCEPROP 3 LASTPIN (-6250 3300) SIG_NAME M_C_CPU1_SB_DQ<22>
J 0
(-6240 3310);
DISPLAY 0.659574 (-6240 3310);
PAINT MONO (-6240 3310);
DISPLAY INVISIBLE (-6240 3310);
FORCEPROP 1 LASTPIN (-6250 3300) BN 22
J 0
(-6262 3308);
DISPLAY 0.489362 (-6262 3308);
PAINT GREEN (-6262 3308);
FORCEPROP 2 LAST CDS_LIB mstr_standard
J 0
(-6200 3300);
DISPLAY 0.723404 (-6200 3300);
PAINT MONO (-6200 3300);
DISPLAY INVISIBLE (-6200 3300);
FORCEPROP 1 LAST BODY_TYPE PLUMBING
J 0
(-6200 3350);
DISPLAY 0.872340 (-6200 3350);
PAINT GREEN (-6200 3350);
DISPLAY INVISIBLE (-6200 3350);
FORCEPROP 1 LAST HDL_TAP TRUE
J 0
(-5875 3175);
DISPLAY 0.872340 (-5875 3175);
DISPLAY INVISIBLE (-5875 3175);
FORCEPROP 1 LAST PATH I56
J 0
(-6202 3300);
DISPLAY 0.872340 (-6202 3300);
PAINT GREEN (-6202 3300);
DISPLAY INVISIBLE (-6202 3300);
FORCEADD TAP..1
(-6200 3250);
FORCEPROP 3 LASTPIN (-6250 3250) SIG_NAME M_C_CPU1_SB_DQ<21>
J 0
(-6240 3260);
DISPLAY 0.659574 (-6240 3260);
PAINT MONO (-6240 3260);
DISPLAY INVISIBLE (-6240 3260);
FORCEPROP 1 LASTPIN (-6250 3250) BN 21
J 0
(-6262 3258);
DISPLAY 0.489362 (-6262 3258);
PAINT GREEN (-6262 3258);
FORCEPROP 2 LAST CDS_LIB mstr_standard
J 0
(-6200 3250);
DISPLAY 0.723404 (-6200 3250);
PAINT MONO (-6200 3250);
DISPLAY INVISIBLE (-6200 3250);
FORCEPROP 1 LAST BODY_TYPE PLUMBING
J 0
(-6200 3300);
DISPLAY 0.872340 (-6200 3300);
PAINT GREEN (-6200 3300);
DISPLAY INVISIBLE (-6200 3300);
FORCEPROP 1 LAST HDL_TAP TRUE
J 0
(-5875 3125);
DISPLAY 0.872340 (-5875 3125);
DISPLAY INVISIBLE (-5875 3125);
FORCEPROP 1 LAST PATH I57
J 0
(-6202 3250);
DISPLAY 0.872340 (-6202 3250);
PAINT GREEN (-6202 3250);
DISPLAY INVISIBLE (-6202 3250);
FORCEADD TAP..1
(-6200 3350);
FORCEPROP 3 LASTPIN (-6250 3350) SIG_NAME M_C_CPU1_SB_DQ<23>
J 0
(-6240 3360);
DISPLAY 0.659574 (-6240 3360);
PAINT MONO (-6240 3360);
DISPLAY INVISIBLE (-6240 3360);
FORCEPROP 1 LASTPIN (-6250 3350) BN 23
J 0
(-6262 3358);
DISPLAY 0.489362 (-6262 3358);
PAINT GREEN (-6262 3358);
FORCEPROP 2 LAST CDS_LIB mstr_standard
J 0
(-6200 3350);
DISPLAY 0.723404 (-6200 3350);
PAINT MONO (-6200 3350);
DISPLAY INVISIBLE (-6200 3350);
FORCEPROP 1 LAST BODY_TYPE PLUMBING
J 0
(-6200 3400);
DISPLAY 0.872340 (-6200 3400);
PAINT GREEN (-6200 3400);
DISPLAY INVISIBLE (-6200 3400);
FORCEPROP 1 LAST HDL_TAP TRUE
J 0
(-5875 3225);
DISPLAY 0.872340 (-5875 3225);
DISPLAY INVISIBLE (-5875 3225);
FORCEPROP 1 LAST PATH I58
J 0
(-6202 3350);
DISPLAY 0.872340 (-6202 3350);
PAINT GREEN (-6202 3350);
DISPLAY INVISIBLE (-6202 3350);
FORCEADD TAP..1
(-6200 3450);
FORCEPROP 3 LASTPIN (-6250 3450) SIG_NAME M_C_CPU1_SB_DQ<25>
J 0
(-6240 3460);
DISPLAY 0.659574 (-6240 3460);
PAINT MONO (-6240 3460);
DISPLAY INVISIBLE (-6240 3460);
FORCEPROP 1 LASTPIN (-6250 3450) BN 25
J 0
(-6262 3458);
DISPLAY 0.489362 (-6262 3458);
PAINT GREEN (-6262 3458);
FORCEPROP 2 LAST CDS_LIB mstr_standard
J 0
(-6200 3450);
DISPLAY 0.723404 (-6200 3450);
PAINT MONO (-6200 3450);
DISPLAY INVISIBLE (-6200 3450);
FORCEPROP 1 LAST BODY_TYPE PLUMBING
J 0
(-6200 3500);
DISPLAY 0.872340 (-6200 3500);
PAINT GREEN (-6200 3500);
DISPLAY INVISIBLE (-6200 3500);
FORCEPROP 1 LAST HDL_TAP TRUE
J 0
(-5875 3325);
DISPLAY 0.872340 (-5875 3325);
DISPLAY INVISIBLE (-5875 3325);
FORCEPROP 1 LAST PATH I59
J 0
(-6202 3450);
DISPLAY 0.872340 (-6202 3450);
PAINT GREEN (-6202 3450);
DISPLAY INVISIBLE (-6202 3450);
FORCEADD VCC_CORE..1
(-8675 3425);
FORCEPROP 3 LASTPIN (-8675 3375) SIG_NAME P3V3_AUX\g
J 0
(-8665 3385);
DISPLAY 0.659574 (-8665 3385);
PAINT MONO (-8665 3385);
DISPLAY INVISIBLE (-8665 3385);
FORCEPROP 1 LAST HDL_POWER P3V3_AUX
J 1
(-8675 3475);
DISPLAY 0.489362 (-8675 3475);
PAINT GREEN (-8675 3475);
FORCEPROP 2 LAST CDS_LIB mstr_symbols
J 0
(-8675 3425);
PAINT MONO (-8675 3425);
DISPLAY INVISIBLE (-8675 3425);
FORCEPROP 0 LAST VOLTAGE 3.3
J 0
(-8950 3575);
DISPLAY 1.021277 (-8950 3575);
PAINT SKYBLUE (-8950 3575);
DISPLAY INVISIBLE (-8950 3575);
FORCEPROP 2 LAST ROOM PVCCINFAON_CPU1_CTRL
J 0
(-8675 3525);
DISPLAY 0.808511 (-8675 3525);
PAINT RED (-8675 3525);
DISPLAY INVISIBLE (-8675 3525);
FORCEPROP 1 LAST PATH I6
J 0
(-8625 3450);
DISPLAY 0.872340 (-8625 3450);
PAINT AQUA (-8625 3450);
DISPLAY INVISIBLE (-8625 3450);
FORCEADD TAP..1
(-6200 3400);
FORCEPROP 3 LASTPIN (-6250 3400) SIG_NAME M_C_CPU1_SB_DQ<24>
J 0
(-6240 3410);
DISPLAY 0.659574 (-6240 3410);
PAINT MONO (-6240 3410);
DISPLAY INVISIBLE (-6240 3410);
FORCEPROP 1 LASTPIN (-6250 3400) BN 24
J 0
(-6262 3408);
DISPLAY 0.489362 (-6262 3408);
PAINT GREEN (-6262 3408);
FORCEPROP 2 LAST CDS_LIB mstr_standard
J 0
(-6200 3400);
DISPLAY 0.723404 (-6200 3400);
PAINT MONO (-6200 3400);
DISPLAY INVISIBLE (-6200 3400);
FORCEPROP 1 LAST BODY_TYPE PLUMBING
J 0
(-6200 3450);
DISPLAY 0.872340 (-6200 3450);
PAINT GREEN (-6200 3450);
DISPLAY INVISIBLE (-6200 3450);
FORCEPROP 1 LAST HDL_TAP TRUE
J 0
(-5875 3275);
DISPLAY 0.872340 (-5875 3275);
DISPLAY INVISIBLE (-5875 3275);
FORCEPROP 1 LAST PATH I60
J 0
(-6202 3400);
DISPLAY 0.872340 (-6202 3400);
PAINT GREEN (-6202 3400);
DISPLAY INVISIBLE (-6202 3400);
FORCEADD TAP..1
(-6200 3500);
FORCEPROP 3 LASTPIN (-6250 3500) SIG_NAME M_C_CPU1_SB_DQ<26>
J 0
(-6240 3510);
DISPLAY 0.659574 (-6240 3510);
PAINT MONO (-6240 3510);
DISPLAY INVISIBLE (-6240 3510);
FORCEPROP 1 LASTPIN (-6250 3500) BN 26
J 0
(-6262 3508);
DISPLAY 0.489362 (-6262 3508);
PAINT GREEN (-6262 3508);
FORCEPROP 2 LAST CDS_LIB mstr_standard
J 0
(-6200 3500);
DISPLAY 0.723404 (-6200 3500);
PAINT MONO (-6200 3500);
DISPLAY INVISIBLE (-6200 3500);
FORCEPROP 1 LAST BODY_TYPE PLUMBING
J 0
(-6200 3550);
DISPLAY 0.872340 (-6200 3550);
PAINT GREEN (-6200 3550);
DISPLAY INVISIBLE (-6200 3550);
FORCEPROP 1 LAST HDL_TAP TRUE
J 0
(-5875 3375);
DISPLAY 0.872340 (-5875 3375);
DISPLAY INVISIBLE (-5875 3375);
FORCEPROP 1 LAST PATH I61
J 0
(-6202 3500);
DISPLAY 0.872340 (-6202 3500);
PAINT GREEN (-6202 3500);
DISPLAY INVISIBLE (-6202 3500);
FORCEADD TAP..1
(-6200 3550);
FORCEPROP 3 LASTPIN (-6250 3550) SIG_NAME M_C_CPU1_SB_DQ<27>
J 0
(-6240 3560);
DISPLAY 0.659574 (-6240 3560);
PAINT MONO (-6240 3560);
DISPLAY INVISIBLE (-6240 3560);
FORCEPROP 1 LASTPIN (-6250 3550) BN 27
J 0
(-6262 3558);
DISPLAY 0.489362 (-6262 3558);
PAINT GREEN (-6262 3558);
FORCEPROP 2 LAST CDS_LIB mstr_standard
J 0
(-6200 3550);
DISPLAY 0.723404 (-6200 3550);
PAINT MONO (-6200 3550);
DISPLAY INVISIBLE (-6200 3550);
FORCEPROP 1 LAST BODY_TYPE PLUMBING
J 0
(-6200 3600);
DISPLAY 0.872340 (-6200 3600);
PAINT GREEN (-6200 3600);
DISPLAY INVISIBLE (-6200 3600);
FORCEPROP 1 LAST HDL_TAP TRUE
J 0
(-5875 3425);
DISPLAY 0.872340 (-5875 3425);
DISPLAY INVISIBLE (-5875 3425);
FORCEPROP 1 LAST PATH I62
J 0
(-6202 3550);
DISPLAY 0.872340 (-6202 3550);
PAINT GREEN (-6202 3550);
DISPLAY INVISIBLE (-6202 3550);
FORCEADD TAP..1
(-6200 3650);
FORCEPROP 3 LASTPIN (-6250 3650) SIG_NAME M_C_CPU1_SB_DQ<29>
J 0
(-6240 3660);
DISPLAY 0.659574 (-6240 3660);
PAINT MONO (-6240 3660);
DISPLAY INVISIBLE (-6240 3660);
FORCEPROP 1 LASTPIN (-6250 3650) BN 29
J 0
(-6262 3658);
DISPLAY 0.489362 (-6262 3658);
PAINT GREEN (-6262 3658);
FORCEPROP 2 LAST CDS_LIB mstr_standard
J 0
(-6200 3650);
DISPLAY 0.723404 (-6200 3650);
PAINT MONO (-6200 3650);
DISPLAY INVISIBLE (-6200 3650);
FORCEPROP 1 LAST BODY_TYPE PLUMBING
J 0
(-6200 3700);
DISPLAY 0.872340 (-6200 3700);
PAINT GREEN (-6200 3700);
DISPLAY INVISIBLE (-6200 3700);
FORCEPROP 1 LAST HDL_TAP TRUE
J 0
(-5875 3525);
DISPLAY 0.872340 (-5875 3525);
DISPLAY INVISIBLE (-5875 3525);
FORCEPROP 1 LAST PATH I63
J 0
(-6202 3650);
DISPLAY 0.872340 (-6202 3650);
PAINT GREEN (-6202 3650);
DISPLAY INVISIBLE (-6202 3650);
FORCEADD TAP..1
(-6200 3700);
FORCEPROP 3 LASTPIN (-6250 3700) SIG_NAME M_C_CPU1_SB_DQ<30>
J 0
(-6240 3710);
DISPLAY 0.659574 (-6240 3710);
PAINT MONO (-6240 3710);
DISPLAY INVISIBLE (-6240 3710);
FORCEPROP 1 LASTPIN (-6250 3700) BN 30
J 0
(-6262 3708);
DISPLAY 0.489362 (-6262 3708);
PAINT GREEN (-6262 3708);
FORCEPROP 2 LAST CDS_LIB mstr_standard
J 0
(-6200 3700);
DISPLAY 0.723404 (-6200 3700);
PAINT MONO (-6200 3700);
DISPLAY INVISIBLE (-6200 3700);
FORCEPROP 1 LAST BODY_TYPE PLUMBING
J 0
(-6200 3750);
DISPLAY 0.872340 (-6200 3750);
PAINT GREEN (-6200 3750);
DISPLAY INVISIBLE (-6200 3750);
FORCEPROP 1 LAST HDL_TAP TRUE
J 0
(-5875 3575);
DISPLAY 0.872340 (-5875 3575);
DISPLAY INVISIBLE (-5875 3575);
FORCEPROP 1 LAST PATH I64
J 0
(-6202 3700);
DISPLAY 0.872340 (-6202 3700);
PAINT GREEN (-6202 3700);
DISPLAY INVISIBLE (-6202 3700);
FORCEADD TAP..1
(-6200 3600);
FORCEPROP 3 LASTPIN (-6250 3600) SIG_NAME M_C_CPU1_SB_DQ<28>
J 0
(-6240 3610);
DISPLAY 0.659574 (-6240 3610);
PAINT MONO (-6240 3610);
DISPLAY INVISIBLE (-6240 3610);
FORCEPROP 1 LASTPIN (-6250 3600) BN 28
J 0
(-6262 3608);
DISPLAY 0.489362 (-6262 3608);
PAINT GREEN (-6262 3608);
FORCEPROP 2 LAST CDS_LIB mstr_standard
J 0
(-6200 3600);
DISPLAY 0.723404 (-6200 3600);
PAINT MONO (-6200 3600);
DISPLAY INVISIBLE (-6200 3600);
FORCEPROP 1 LAST BODY_TYPE PLUMBING
J 0
(-6200 3650);
DISPLAY 0.872340 (-6200 3650);
PAINT GREEN (-6200 3650);
DISPLAY INVISIBLE (-6200 3650);
FORCEPROP 1 LAST HDL_TAP TRUE
J 0
(-5875 3475);
DISPLAY 0.872340 (-5875 3475);
DISPLAY INVISIBLE (-5875 3475);
FORCEPROP 1 LAST PATH I65
J 0
(-6202 3600);
DISPLAY 0.872340 (-6202 3600);
PAINT GREEN (-6202 3600);
DISPLAY INVISIBLE (-6202 3600);
FORCEADD TAP..1
(-6200 3750);
FORCEPROP 3 LASTPIN (-6250 3750) SIG_NAME M_C_CPU1_SB_DQ<31>
J 0
(-6240 3760);
DISPLAY 0.659574 (-6240 3760);
PAINT MONO (-6240 3760);
DISPLAY INVISIBLE (-6240 3760);
FORCEPROP 1 LASTPIN (-6250 3750) BN 31
J 0
(-6262 3758);
DISPLAY 0.489362 (-6262 3758);
PAINT GREEN (-6262 3758);
FORCEPROP 2 LAST CDS_LIB mstr_standard
J 0
(-6200 3750);
DISPLAY 0.723404 (-6200 3750);
PAINT MONO (-6200 3750);
DISPLAY INVISIBLE (-6200 3750);
FORCEPROP 1 LAST BODY_TYPE PLUMBING
J 0
(-6200 3800);
DISPLAY 0.872340 (-6200 3800);
PAINT GREEN (-6200 3800);
DISPLAY INVISIBLE (-6200 3800);
FORCEPROP 1 LAST HDL_TAP TRUE
J 0
(-5875 3625);
DISPLAY 0.872340 (-5875 3625);
DISPLAY INVISIBLE (-5875 3625);
FORCEPROP 1 LAST PATH I66
J 0
(-6202 3750);
DISPLAY 0.872340 (-6202 3750);
PAINT GREEN (-6202 3750);
DISPLAY INVISIBLE (-6202 3750);
FORCEADD OFFPAGE..5
(-8325 3050);
FORCEPROP 2 LAST $XR0 39 
J 0
(-8549 3050);
DISPLAY 0.638298 (-8549 3050);
PAINT MONO (-8549 3050);
FORCEPROP 2 LAST CDS_LIB mstr_standard
J 0
(-8325 3050);
DISPLAY INVISIBLE (-8325 3050);
FORCEPROP 1 LAST OFFPAGE TRUE
J 0
(-8000 2925);
DISPLAY 0.872340 (-8000 2925);
PAINT GREEN (-8000 2925);
DISPLAY INVISIBLE (-8000 2925);
FORCEPROP 1 LAST COMMENT_BODY TRUE
J 0
(-8225 2975);
DISPLAY 0.872340 (-8225 2975);
PAINT GREEN (-8225 2975);
DISPLAY INVISIBLE (-8225 2975);
FORCEPROP 2 LAST PATH I7
J 0
(-8575 3100);
DISPLAY 1.021277 (-8575 3100);
DISPLAY INVISIBLE (-8575 3100);
FORCEADD OFFPAGE..3
(-5600 3800);
FORCEPROP 2 LAST $XR0 39 
J 0
(-5386 3800);
DISPLAY 0.638298 (-5386 3800);
PAINT MONO (-5386 3800);
FORCEPROP 2 LAST CDS_LIB mstr_standard
J 0
(-5600 3800);
DISPLAY 0.723404 (-5600 3800);
PAINT MONO (-5600 3800);
DISPLAY INVISIBLE (-5600 3800);
FORCEPROP 1 LAST OFFPAGE TRUE
J 0
(-5275 3675);
DISPLAY 0.872340 (-5275 3675);
PAINT GREEN (-5275 3675);
DISPLAY INVISIBLE (-5275 3675);
FORCEPROP 1 LAST COMMENT_BODY TRUE
J 0
(-5650 3700);
DISPLAY 0.872340 (-5650 3700);
PAINT GREEN (-5650 3700);
DISPLAY INVISIBLE (-5650 3700);
FORCEPROP 2 LAST PATH I74
J 0
(-5375 3850);
DISPLAY 1.021277 (-5375 3850);
DISPLAY INVISIBLE (-5375 3850);
FORCEADD TAP..1
R 2
(-7900 3850);
FORCEPROP 3 LASTPIN (-7850 3850) SIG_NAME M_C_CPU1_SA_CB<4>
J 0
(-7840 3860);
DISPLAY 0.659574 (-7840 3860);
PAINT MONO (-7840 3860);
DISPLAY INVISIBLE (-7840 3860);
FORCEPROP 1 LASTPIN (-7850 3850) BN 4
J 2
(-7838 3858);
DISPLAY 0.489362 (-7838 3858);
PAINT GREEN (-7838 3858);
FORCEPROP 2 LAST CDS_LIB mstr_standard
J 0
(-7900 3850);
DISPLAY 0.723404 (-7900 3850);
PAINT MONO (-7900 3850);
DISPLAY INVISIBLE (-7900 3850);
FORCEPROP 1 LAST BODY_TYPE PLUMBING
J 2
(-7900 3900);
DISPLAY 0.872340 (-7900 3900);
PAINT GREEN (-7900 3900);
DISPLAY INVISIBLE (-7900 3900);
FORCEPROP 1 LAST HDL_TAP TRUE
J 2
(-8225 3725);
DISPLAY 0.872340 (-8225 3725);
DISPLAY INVISIBLE (-8225 3725);
FORCEPROP 1 LAST PATH I79
J 2
(-7898 3850);
DISPLAY 0.872340 (-7898 3850);
PAINT GREEN (-7898 3850);
DISPLAY INVISIBLE (-7898 3850);
FORCEADD OFFPAGE..1
(-8725 2900);
FORCEPROP 2 LAST $XR0 100 
J 0
(-8977 2900);
DISPLAY 0.638298 (-8977 2900);
PAINT MONO (-8977 2900);
FORCEPROP 2 LAST CDS_LIB mstr_standard
J 0
(-8725 2900);
DISPLAY 0.808511 (-8725 2900);
DISPLAY INVISIBLE (-8725 2900);
FORCEPROP 1 LAST OFFPAGE TRUE
J 0
(-8400 2775);
DISPLAY 0.872340 (-8400 2775);
PAINT GREEN (-8400 2775);
DISPLAY INVISIBLE (-8400 2775);
FORCEPROP 1 LAST COMMENT_BODY TRUE
J 0
(-8600 2800);
DISPLAY 0.872340 (-8600 2800);
PAINT GREEN (-8600 2800);
DISPLAY INVISIBLE (-8600 2800);
FORCEPROP 2 LAST PATH I8
J 0
(-8975 2950);
DISPLAY 1.021277 (-8975 2950);
DISPLAY INVISIBLE (-8975 2950);
FORCEADD TAP..1
R 2
(-7900 3900);
FORCEPROP 3 LASTPIN (-7850 3900) SIG_NAME M_C_CPU1_SA_CB<5>
J 0
(-7840 3910);
DISPLAY 0.659574 (-7840 3910);
PAINT MONO (-7840 3910);
DISPLAY INVISIBLE (-7840 3910);
FORCEPROP 1 LASTPIN (-7850 3900) BN 5
J 2
(-7838 3908);
DISPLAY 0.489362 (-7838 3908);
PAINT GREEN (-7838 3908);
FORCEPROP 2 LAST CDS_LIB mstr_standard
J 0
(-7900 3900);
DISPLAY 0.723404 (-7900 3900);
PAINT MONO (-7900 3900);
DISPLAY INVISIBLE (-7900 3900);
FORCEPROP 1 LAST BODY_TYPE PLUMBING
J 2
(-7900 3950);
DISPLAY 0.872340 (-7900 3950);
PAINT GREEN (-7900 3950);
DISPLAY INVISIBLE (-7900 3950);
FORCEPROP 1 LAST HDL_TAP TRUE
J 2
(-8225 3775);
DISPLAY 0.872340 (-8225 3775);
DISPLAY INVISIBLE (-8225 3775);
FORCEPROP 1 LAST PATH I80
J 2
(-7898 3900);
DISPLAY 0.872340 (-7898 3900);
PAINT GREEN (-7898 3900);
DISPLAY INVISIBLE (-7898 3900);
FORCEADD TAP..1
R 2
(-7900 3950);
FORCEPROP 3 LASTPIN (-7850 3950) SIG_NAME M_C_CPU1_SA_CB<6>
J 0
(-7840 3960);
DISPLAY 0.659574 (-7840 3960);
PAINT MONO (-7840 3960);
DISPLAY INVISIBLE (-7840 3960);
FORCEPROP 1 LASTPIN (-7850 3950) BN 6
J 2
(-7838 3958);
DISPLAY 0.489362 (-7838 3958);
PAINT GREEN (-7838 3958);
FORCEPROP 2 LAST CDS_LIB mstr_standard
J 0
(-7900 3950);
DISPLAY 0.723404 (-7900 3950);
PAINT MONO (-7900 3950);
DISPLAY INVISIBLE (-7900 3950);
FORCEPROP 1 LAST BODY_TYPE PLUMBING
J 2
(-7900 4000);
DISPLAY 0.872340 (-7900 4000);
PAINT GREEN (-7900 4000);
DISPLAY INVISIBLE (-7900 4000);
FORCEPROP 1 LAST HDL_TAP TRUE
J 2
(-8225 3825);
DISPLAY 0.872340 (-8225 3825);
DISPLAY INVISIBLE (-8225 3825);
FORCEPROP 1 LAST PATH I81
J 2
(-7898 3950);
DISPLAY 0.872340 (-7898 3950);
PAINT GREEN (-7898 3950);
DISPLAY INVISIBLE (-7898 3950);
FORCEADD TAP..1
R 2
(-7900 4000);
FORCEPROP 3 LASTPIN (-7850 4000) SIG_NAME M_C_CPU1_SA_CB<7>
J 0
(-7840 4010);
DISPLAY 0.659574 (-7840 4010);
PAINT MONO (-7840 4010);
DISPLAY INVISIBLE (-7840 4010);
FORCEPROP 1 LASTPIN (-7850 4000) BN 7
J 2
(-7838 4008);
DISPLAY 0.489362 (-7838 4008);
PAINT GREEN (-7838 4008);
FORCEPROP 2 LAST CDS_LIB mstr_standard
J 0
(-7900 4000);
DISPLAY 0.723404 (-7900 4000);
PAINT MONO (-7900 4000);
DISPLAY INVISIBLE (-7900 4000);
FORCEPROP 1 LAST BODY_TYPE PLUMBING
J 2
(-7900 4050);
DISPLAY 0.872340 (-7900 4050);
PAINT GREEN (-7900 4050);
DISPLAY INVISIBLE (-7900 4050);
FORCEPROP 1 LAST HDL_TAP TRUE
J 2
(-8225 3875);
DISPLAY 0.872340 (-8225 3875);
DISPLAY INVISIBLE (-8225 3875);
FORCEPROP 1 LAST PATH I82
J 2
(-7898 4000);
DISPLAY 0.872340 (-7898 4000);
PAINT GREEN (-7898 4000);
DISPLAY INVISIBLE (-7898 4000);
FORCEADD TAP..1
R 2
(-7900 4700);
FORCEPROP 3 LASTPIN (-7850 4700) SIG_NAME M_C_CPU1_SB_CA<0>
J 0
(-7840 4710);
DISPLAY 0.659574 (-7840 4710);
PAINT MONO (-7840 4710);
DISPLAY INVISIBLE (-7840 4710);
FORCEPROP 1 LASTPIN (-7850 4700) BN 0
J 2
(-7838 4708);
DISPLAY 0.489362 (-7838 4708);
PAINT GREEN (-7838 4708);
FORCEPROP 2 LAST CDS_LIB mstr_standard
J 0
(-7900 4700);
DISPLAY 0.723404 (-7900 4700);
PAINT MONO (-7900 4700);
DISPLAY INVISIBLE (-7900 4700);
FORCEPROP 1 LAST BODY_TYPE PLUMBING
J 2
(-7900 4750);
DISPLAY 0.872340 (-7900 4750);
PAINT GREEN (-7900 4750);
DISPLAY INVISIBLE (-7900 4750);
FORCEPROP 1 LAST HDL_TAP TRUE
J 2
(-8225 4575);
DISPLAY 0.872340 (-8225 4575);
DISPLAY INVISIBLE (-8225 4575);
FORCEPROP 1 LAST PATH I83
J 2
(-7898 4700);
DISPLAY 0.872340 (-7898 4700);
PAINT GREEN (-7898 4700);
DISPLAY INVISIBLE (-7898 4700);
FORCEADD TAP..1
R 2
(-7900 4800);
FORCEPROP 3 LASTPIN (-7850 4800) SIG_NAME M_C_CPU1_SB_CA<2>
J 0
(-7840 4810);
DISPLAY 0.659574 (-7840 4810);
PAINT MONO (-7840 4810);
DISPLAY INVISIBLE (-7840 4810);
FORCEPROP 1 LASTPIN (-7850 4800) BN 2
J 2
(-7838 4808);
DISPLAY 0.489362 (-7838 4808);
PAINT GREEN (-7838 4808);
FORCEPROP 2 LAST CDS_LIB mstr_standard
J 0
(-7900 4800);
DISPLAY 0.723404 (-7900 4800);
PAINT MONO (-7900 4800);
DISPLAY INVISIBLE (-7900 4800);
FORCEPROP 1 LAST BODY_TYPE PLUMBING
J 2
(-7900 4850);
DISPLAY 0.872340 (-7900 4850);
PAINT GREEN (-7900 4850);
DISPLAY INVISIBLE (-7900 4850);
FORCEPROP 1 LAST HDL_TAP TRUE
J 2
(-8225 4675);
DISPLAY 0.872340 (-8225 4675);
DISPLAY INVISIBLE (-8225 4675);
FORCEPROP 1 LAST PATH I84
J 2
(-7898 4800);
DISPLAY 0.872340 (-7898 4800);
PAINT GREEN (-7898 4800);
DISPLAY INVISIBLE (-7898 4800);
FORCEADD TAP..1
R 2
(-7900 4750);
FORCEPROP 3 LASTPIN (-7850 4750) SIG_NAME M_C_CPU1_SB_CA<1>
J 0
(-7840 4760);
DISPLAY 0.659574 (-7840 4760);
PAINT MONO (-7840 4760);
DISPLAY INVISIBLE (-7840 4760);
FORCEPROP 1 LASTPIN (-7850 4750) BN 1
J 2
(-7838 4758);
DISPLAY 0.489362 (-7838 4758);
PAINT GREEN (-7838 4758);
FORCEPROP 2 LAST CDS_LIB mstr_standard
J 0
(-7900 4750);
DISPLAY 0.723404 (-7900 4750);
PAINT MONO (-7900 4750);
DISPLAY INVISIBLE (-7900 4750);
FORCEPROP 1 LAST BODY_TYPE PLUMBING
J 2
(-7900 4800);
DISPLAY 0.872340 (-7900 4800);
PAINT GREEN (-7900 4800);
DISPLAY INVISIBLE (-7900 4800);
FORCEPROP 1 LAST HDL_TAP TRUE
J 2
(-8225 4625);
DISPLAY 0.872340 (-8225 4625);
DISPLAY INVISIBLE (-8225 4625);
FORCEPROP 1 LAST PATH I85
J 2
(-7898 4750);
DISPLAY 0.872340 (-7898 4750);
PAINT GREEN (-7898 4750);
DISPLAY INVISIBLE (-7898 4750);
FORCEADD TAP..1
R 2
(-7900 4850);
FORCEPROP 3 LASTPIN (-7850 4850) SIG_NAME M_C_CPU1_SB_CA<3>
J 0
(-7840 4860);
DISPLAY 0.659574 (-7840 4860);
PAINT MONO (-7840 4860);
DISPLAY INVISIBLE (-7840 4860);
FORCEPROP 1 LASTPIN (-7850 4850) BN 3
J 2
(-7838 4858);
DISPLAY 0.489362 (-7838 4858);
PAINT GREEN (-7838 4858);
FORCEPROP 2 LAST CDS_LIB mstr_standard
J 0
(-7900 4850);
DISPLAY 0.723404 (-7900 4850);
PAINT MONO (-7900 4850);
DISPLAY INVISIBLE (-7900 4850);
FORCEPROP 1 LAST BODY_TYPE PLUMBING
J 2
(-7900 4900);
DISPLAY 0.872340 (-7900 4900);
PAINT GREEN (-7900 4900);
DISPLAY INVISIBLE (-7900 4900);
FORCEPROP 1 LAST HDL_TAP TRUE
J 2
(-8225 4725);
DISPLAY 0.872340 (-8225 4725);
DISPLAY INVISIBLE (-8225 4725);
FORCEPROP 1 LAST PATH I86
J 2
(-7898 4850);
DISPLAY 0.872340 (-7898 4850);
PAINT GREEN (-7898 4850);
DISPLAY INVISIBLE (-7898 4850);
FORCEADD TAP..1
R 2
(-7900 4900);
FORCEPROP 3 LASTPIN (-7850 4900) SIG_NAME M_C_CPU1_SB_CA<4>
J 0
(-7840 4910);
DISPLAY 0.659574 (-7840 4910);
PAINT MONO (-7840 4910);
DISPLAY INVISIBLE (-7840 4910);
FORCEPROP 1 LASTPIN (-7850 4900) BN 4
J 2
(-7838 4908);
DISPLAY 0.489362 (-7838 4908);
PAINT GREEN (-7838 4908);
FORCEPROP 2 LAST CDS_LIB mstr_standard
J 0
(-7900 4900);
DISPLAY 0.723404 (-7900 4900);
PAINT MONO (-7900 4900);
DISPLAY INVISIBLE (-7900 4900);
FORCEPROP 1 LAST BODY_TYPE PLUMBING
J 2
(-7900 4950);
DISPLAY 0.872340 (-7900 4950);
PAINT GREEN (-7900 4950);
DISPLAY INVISIBLE (-7900 4950);
FORCEPROP 1 LAST HDL_TAP TRUE
J 2
(-8225 4775);
DISPLAY 0.872340 (-8225 4775);
DISPLAY INVISIBLE (-8225 4775);
FORCEPROP 1 LAST PATH I87
J 2
(-7898 4900);
DISPLAY 0.872340 (-7898 4900);
PAINT GREEN (-7898 4900);
DISPLAY INVISIBLE (-7898 4900);
FORCEADD TAP..1
R 2
(-7900 4950);
FORCEPROP 3 LASTPIN (-7850 4950) SIG_NAME M_C_CPU1_SB_CA<5>
J 0
(-7840 4960);
DISPLAY 0.659574 (-7840 4960);
PAINT MONO (-7840 4960);
DISPLAY INVISIBLE (-7840 4960);
FORCEPROP 1 LASTPIN (-7850 4950) BN 5
J 2
(-7838 4958);
DISPLAY 0.489362 (-7838 4958);
PAINT GREEN (-7838 4958);
FORCEPROP 2 LAST CDS_LIB mstr_standard
J 0
(-7900 4950);
DISPLAY 0.723404 (-7900 4950);
PAINT MONO (-7900 4950);
DISPLAY INVISIBLE (-7900 4950);
FORCEPROP 1 LAST BODY_TYPE PLUMBING
J 2
(-7900 5000);
DISPLAY 0.872340 (-7900 5000);
PAINT GREEN (-7900 5000);
DISPLAY INVISIBLE (-7900 5000);
FORCEPROP 1 LAST HDL_TAP TRUE
J 2
(-8225 4825);
DISPLAY 0.872340 (-8225 4825);
DISPLAY INVISIBLE (-8225 4825);
FORCEPROP 1 LAST PATH I88
J 2
(-7898 4950);
DISPLAY 0.872340 (-7898 4950);
PAINT GREEN (-7898 4950);
DISPLAY INVISIBLE (-7898 4950);
FORCEADD TAP..1
R 2
(-7900 5000);
FORCEPROP 3 LASTPIN (-7850 5000) SIG_NAME M_C_CPU1_SB_CA<6>
J 0
(-7840 5010);
DISPLAY 0.659574 (-7840 5010);
PAINT MONO (-7840 5010);
DISPLAY INVISIBLE (-7840 5010);
FORCEPROP 1 LASTPIN (-7850 5000) BN 6
J 2
(-7838 5008);
DISPLAY 0.489362 (-7838 5008);
PAINT GREEN (-7838 5008);
FORCEPROP 2 LAST CDS_LIB mstr_standard
J 0
(-7900 5000);
DISPLAY 0.723404 (-7900 5000);
PAINT MONO (-7900 5000);
DISPLAY INVISIBLE (-7900 5000);
FORCEPROP 1 LAST BODY_TYPE PLUMBING
J 2
(-7900 5050);
DISPLAY 0.872340 (-7900 5050);
PAINT GREEN (-7900 5050);
DISPLAY INVISIBLE (-7900 5050);
FORCEPROP 1 LAST HDL_TAP TRUE
J 2
(-8225 4875);
DISPLAY 0.872340 (-8225 4875);
DISPLAY INVISIBLE (-8225 4875);
FORCEPROP 1 LAST PATH I89
J 2
(-7898 5000);
DISPLAY 0.872340 (-7898 5000);
PAINT GREEN (-7898 5000);
DISPLAY INVISIBLE (-7898 5000);
FORCEADD OFFPAGE..1
(-8325 3100);
FORCEPROP 2 LAST $XR0 39 
J 0
(-8546 3100);
DISPLAY 0.638298 (-8546 3100);
PAINT MONO (-8546 3100);
FORCEPROP 2 LAST CDS_LIB mstr_standard
J 0
(-8325 3100);
DISPLAY 0.808511 (-8325 3100);
DISPLAY INVISIBLE (-8325 3100);
FORCEPROP 1 LAST OFFPAGE TRUE
J 0
(-8000 2975);
DISPLAY 0.872340 (-8000 2975);
PAINT GREEN (-8000 2975);
DISPLAY INVISIBLE (-8000 2975);
FORCEPROP 1 LAST COMMENT_BODY TRUE
J 0
(-8200 3000);
DISPLAY 0.872340 (-8200 3000);
PAINT GREEN (-8200 3000);
DISPLAY INVISIBLE (-8200 3000);
FORCEPROP 2 LAST PATH I9
J 0
(-8525 3150);
DISPLAY 1.021277 (-8525 3150);
DISPLAY INVISIBLE (-8525 3150);
FORCEADD TAP..1
R 2
(-7900 5100);
FORCEPROP 3 LASTPIN (-7850 5100) SIG_NAME M_C_CPU1_SA_CA<0>
J 0
(-7840 5110);
DISPLAY 0.659574 (-7840 5110);
PAINT MONO (-7840 5110);
DISPLAY INVISIBLE (-7840 5110);
FORCEPROP 1 LASTPIN (-7850 5100) BN 0
J 2
(-7838 5108);
DISPLAY 0.489362 (-7838 5108);
PAINT GREEN (-7838 5108);
FORCEPROP 2 LAST CDS_LIB mstr_standard
J 0
(-7900 5100);
DISPLAY 0.723404 (-7900 5100);
PAINT MONO (-7900 5100);
DISPLAY INVISIBLE (-7900 5100);
FORCEPROP 1 LAST BODY_TYPE PLUMBING
J 2
(-7900 5150);
DISPLAY 0.872340 (-7900 5150);
PAINT GREEN (-7900 5150);
DISPLAY INVISIBLE (-7900 5150);
FORCEPROP 1 LAST HDL_TAP TRUE
J 2
(-8225 4975);
DISPLAY 0.872340 (-8225 4975);
DISPLAY INVISIBLE (-8225 4975);
FORCEPROP 1 LAST PATH I90
J 2
(-7898 5100);
DISPLAY 0.872340 (-7898 5100);
PAINT GREEN (-7898 5100);
DISPLAY INVISIBLE (-7898 5100);
FORCEADD TAP..1
R 2
(-7900 5150);
FORCEPROP 3 LASTPIN (-7850 5150) SIG_NAME M_C_CPU1_SA_CA<1>
J 0
(-7840 5160);
DISPLAY 0.659574 (-7840 5160);
PAINT MONO (-7840 5160);
DISPLAY INVISIBLE (-7840 5160);
FORCEPROP 1 LASTPIN (-7850 5150) BN 1
J 2
(-7838 5158);
DISPLAY 0.489362 (-7838 5158);
PAINT GREEN (-7838 5158);
FORCEPROP 2 LAST CDS_LIB mstr_standard
J 0
(-7900 5150);
DISPLAY 0.723404 (-7900 5150);
PAINT MONO (-7900 5150);
DISPLAY INVISIBLE (-7900 5150);
FORCEPROP 1 LAST BODY_TYPE PLUMBING
J 2
(-7900 5200);
DISPLAY 0.872340 (-7900 5200);
PAINT GREEN (-7900 5200);
DISPLAY INVISIBLE (-7900 5200);
FORCEPROP 1 LAST HDL_TAP TRUE
J 2
(-8225 5025);
DISPLAY 0.872340 (-8225 5025);
DISPLAY INVISIBLE (-8225 5025);
FORCEPROP 1 LAST PATH I91
J 2
(-7898 5150);
DISPLAY 0.872340 (-7898 5150);
PAINT GREEN (-7898 5150);
DISPLAY INVISIBLE (-7898 5150);
FORCEADD TAP..1
R 2
(-7900 5200);
FORCEPROP 3 LASTPIN (-7850 5200) SIG_NAME M_C_CPU1_SA_CA<2>
J 0
(-7840 5210);
DISPLAY 0.659574 (-7840 5210);
PAINT MONO (-7840 5210);
DISPLAY INVISIBLE (-7840 5210);
FORCEPROP 1 LASTPIN (-7850 5200) BN 2
J 2
(-7838 5208);
DISPLAY 0.489362 (-7838 5208);
PAINT GREEN (-7838 5208);
FORCEPROP 2 LAST CDS_LIB mstr_standard
J 0
(-7900 5200);
DISPLAY 0.723404 (-7900 5200);
PAINT MONO (-7900 5200);
DISPLAY INVISIBLE (-7900 5200);
FORCEPROP 1 LAST BODY_TYPE PLUMBING
J 2
(-7900 5250);
DISPLAY 0.872340 (-7900 5250);
PAINT GREEN (-7900 5250);
DISPLAY INVISIBLE (-7900 5250);
FORCEPROP 1 LAST HDL_TAP TRUE
J 2
(-8225 5075);
DISPLAY 0.872340 (-8225 5075);
DISPLAY INVISIBLE (-8225 5075);
FORCEPROP 1 LAST PATH I92
J 2
(-7898 5200);
DISPLAY 0.872340 (-7898 5200);
PAINT GREEN (-7898 5200);
DISPLAY INVISIBLE (-7898 5200);
FORCEADD TAP..1
R 2
(-7900 5250);
FORCEPROP 3 LASTPIN (-7850 5250) SIG_NAME M_C_CPU1_SA_CA<3>
J 0
(-7840 5260);
DISPLAY 0.659574 (-7840 5260);
PAINT MONO (-7840 5260);
DISPLAY INVISIBLE (-7840 5260);
FORCEPROP 1 LASTPIN (-7850 5250) BN 3
J 2
(-7838 5258);
DISPLAY 0.489362 (-7838 5258);
PAINT GREEN (-7838 5258);
FORCEPROP 2 LAST CDS_LIB mstr_standard
J 0
(-7900 5250);
DISPLAY 0.723404 (-7900 5250);
PAINT MONO (-7900 5250);
DISPLAY INVISIBLE (-7900 5250);
FORCEPROP 1 LAST BODY_TYPE PLUMBING
J 2
(-7900 5300);
DISPLAY 0.872340 (-7900 5300);
PAINT GREEN (-7900 5300);
DISPLAY INVISIBLE (-7900 5300);
FORCEPROP 1 LAST HDL_TAP TRUE
J 2
(-8225 5125);
DISPLAY 0.872340 (-8225 5125);
DISPLAY INVISIBLE (-8225 5125);
FORCEPROP 1 LAST PATH I93
J 2
(-7898 5250);
DISPLAY 0.872340 (-7898 5250);
PAINT GREEN (-7898 5250);
DISPLAY INVISIBLE (-7898 5250);
FORCEADD TAP..1
R 2
(-7900 5350);
FORCEPROP 3 LASTPIN (-7850 5350) SIG_NAME M_C_CPU1_SA_CA<5>
J 0
(-7840 5360);
DISPLAY 0.659574 (-7840 5360);
PAINT MONO (-7840 5360);
DISPLAY INVISIBLE (-7840 5360);
FORCEPROP 1 LASTPIN (-7850 5350) BN 5
J 2
(-7838 5358);
DISPLAY 0.489362 (-7838 5358);
PAINT GREEN (-7838 5358);
FORCEPROP 2 LAST CDS_LIB mstr_standard
J 0
(-7900 5350);
DISPLAY 0.723404 (-7900 5350);
PAINT MONO (-7900 5350);
DISPLAY INVISIBLE (-7900 5350);
FORCEPROP 1 LAST BODY_TYPE PLUMBING
J 2
(-7900 5400);
DISPLAY 0.872340 (-7900 5400);
PAINT GREEN (-7900 5400);
DISPLAY INVISIBLE (-7900 5400);
FORCEPROP 1 LAST HDL_TAP TRUE
J 2
(-8225 5225);
DISPLAY 0.872340 (-8225 5225);
DISPLAY INVISIBLE (-8225 5225);
FORCEPROP 1 LAST PATH I94
J 2
(-7898 5350);
DISPLAY 0.872340 (-7898 5350);
PAINT GREEN (-7898 5350);
DISPLAY INVISIBLE (-7898 5350);
FORCEADD TAP..1
R 2
(-7900 5300);
FORCEPROP 3 LASTPIN (-7850 5300) SIG_NAME M_C_CPU1_SA_CA<4>
J 0
(-7840 5310);
DISPLAY 0.659574 (-7840 5310);
PAINT MONO (-7840 5310);
DISPLAY INVISIBLE (-7840 5310);
FORCEPROP 1 LASTPIN (-7850 5300) BN 4
J 2
(-7838 5308);
DISPLAY 0.489362 (-7838 5308);
PAINT GREEN (-7838 5308);
FORCEPROP 2 LAST CDS_LIB mstr_standard
J 0
(-7900 5300);
DISPLAY 0.723404 (-7900 5300);
PAINT MONO (-7900 5300);
DISPLAY INVISIBLE (-7900 5300);
FORCEPROP 1 LAST BODY_TYPE PLUMBING
J 2
(-7900 5350);
DISPLAY 0.872340 (-7900 5350);
PAINT GREEN (-7900 5350);
DISPLAY INVISIBLE (-7900 5350);
FORCEPROP 1 LAST HDL_TAP TRUE
J 2
(-8225 5175);
DISPLAY 0.872340 (-8225 5175);
DISPLAY INVISIBLE (-8225 5175);
FORCEPROP 1 LAST PATH I95
J 2
(-7898 5300);
DISPLAY 0.872340 (-7898 5300);
PAINT GREEN (-7898 5300);
DISPLAY INVISIBLE (-7898 5300);
FORCEADD TAP..1
R 2
(-7900 5400);
FORCEPROP 3 LASTPIN (-7850 5400) SIG_NAME M_C_CPU1_SA_CA<6>
J 0
(-7840 5410);
DISPLAY 0.659574 (-7840 5410);
PAINT MONO (-7840 5410);
DISPLAY INVISIBLE (-7840 5410);
FORCEPROP 1 LASTPIN (-7850 5400) BN 6
J 2
(-7838 5408);
DISPLAY 0.489362 (-7838 5408);
PAINT GREEN (-7838 5408);
FORCEPROP 2 LAST CDS_LIB mstr_standard
J 0
(-7900 5400);
DISPLAY 0.723404 (-7900 5400);
PAINT MONO (-7900 5400);
DISPLAY INVISIBLE (-7900 5400);
FORCEPROP 1 LAST BODY_TYPE PLUMBING
J 2
(-7900 5450);
DISPLAY 0.872340 (-7900 5450);
PAINT GREEN (-7900 5450);
DISPLAY INVISIBLE (-7900 5450);
FORCEPROP 1 LAST HDL_TAP TRUE
J 2
(-8225 5275);
DISPLAY 0.872340 (-8225 5275);
DISPLAY INVISIBLE (-8225 5275);
FORCEPROP 1 LAST PATH I96
J 2
(-7898 5400);
DISPLAY 0.872340 (-7898 5400);
PAINT GREEN (-7898 5400);
DISPLAY INVISIBLE (-7898 5400);
FORCEADD TAP..1
(-6200 3850);
FORCEPROP 3 LASTPIN (-6250 3850) SIG_NAME M_C_CPU1_SA_DQ<0>
J 0
(-6240 3860);
DISPLAY 0.659574 (-6240 3860);
PAINT MONO (-6240 3860);
DISPLAY INVISIBLE (-6240 3860);
FORCEPROP 1 LASTPIN (-6250 3850) BN 0
J 0
(-6262 3858);
DISPLAY 0.489362 (-6262 3858);
PAINT GREEN (-6262 3858);
FORCEPROP 2 LAST CDS_LIB mstr_standard
J 0
(-6200 3850);
DISPLAY 0.723404 (-6200 3850);
PAINT MONO (-6200 3850);
DISPLAY INVISIBLE (-6200 3850);
FORCEPROP 1 LAST BODY_TYPE PLUMBING
J 0
(-6200 3900);
DISPLAY 0.872340 (-6200 3900);
PAINT GREEN (-6200 3900);
DISPLAY INVISIBLE (-6200 3900);
FORCEPROP 1 LAST HDL_TAP TRUE
J 0
(-5875 3725);
DISPLAY 0.872340 (-5875 3725);
DISPLAY INVISIBLE (-5875 3725);
FORCEPROP 1 LAST PATH I97
J 0
(-6202 3850);
DISPLAY 0.872340 (-6202 3850);
PAINT GREEN (-6202 3850);
DISPLAY INVISIBLE (-6202 3850);
FORCEADD TAP..1
(-6200 3950);
FORCEPROP 3 LASTPIN (-6250 3950) SIG_NAME M_C_CPU1_SA_DQ<2>
J 0
(-6240 3960);
DISPLAY 0.659574 (-6240 3960);
PAINT MONO (-6240 3960);
DISPLAY INVISIBLE (-6240 3960);
FORCEPROP 1 LASTPIN (-6250 3950) BN 2
J 0
(-6262 3958);
DISPLAY 0.489362 (-6262 3958);
PAINT GREEN (-6262 3958);
FORCEPROP 2 LAST CDS_LIB mstr_standard
J 0
(-6200 3950);
DISPLAY 0.723404 (-6200 3950);
PAINT MONO (-6200 3950);
DISPLAY INVISIBLE (-6200 3950);
FORCEPROP 1 LAST BODY_TYPE PLUMBING
J 0
(-6200 4000);
DISPLAY 0.872340 (-6200 4000);
PAINT GREEN (-6200 4000);
DISPLAY INVISIBLE (-6200 4000);
FORCEPROP 1 LAST HDL_TAP TRUE
J 0
(-5875 3825);
DISPLAY 0.872340 (-5875 3825);
DISPLAY INVISIBLE (-5875 3825);
FORCEPROP 1 LAST PATH I98
J 0
(-6202 3950);
DISPLAY 0.872340 (-6202 3950);
PAINT GREEN (-6202 3950);
DISPLAY INVISIBLE (-6202 3950);
FORCEADD TAP..1
(-6200 3900);
FORCEPROP 3 LASTPIN (-6250 3900) SIG_NAME M_C_CPU1_SA_DQ<1>
J 0
(-6240 3910);
DISPLAY 0.659574 (-6240 3910);
PAINT MONO (-6240 3910);
DISPLAY INVISIBLE (-6240 3910);
FORCEPROP 1 LASTPIN (-6250 3900) BN 1
J 0
(-6262 3908);
DISPLAY 0.489362 (-6262 3908);
PAINT GREEN (-6262 3908);
FORCEPROP 2 LAST CDS_LIB mstr_standard
J 0
(-6200 3900);
DISPLAY 0.723404 (-6200 3900);
PAINT MONO (-6200 3900);
DISPLAY INVISIBLE (-6200 3900);
FORCEPROP 1 LAST BODY_TYPE PLUMBING
J 0
(-6200 3950);
DISPLAY 0.872340 (-6200 3950);
PAINT GREEN (-6200 3950);
DISPLAY INVISIBLE (-6200 3950);
FORCEPROP 1 LAST HDL_TAP TRUE
J 0
(-5875 3775);
DISPLAY 0.872340 (-5875 3775);
DISPLAY INVISIBLE (-5875 3775);
FORCEPROP 1 LAST PATH I99
J 0
(-6202 3900);
DISPLAY 0.872340 (-6202 3900);
PAINT GREEN (-6202 3900);
DISPLAY INVISIBLE (-6202 3900);
FORCEADD DNS..2
(-8550 2300);
PAINT RED (-8550 2300);
FORCEPROP 2 LAST CDS_LIB mstr_misc
J 0
(-8550 2300);
DISPLAY INVISIBLE (-8550 2300);
FORCEPROP 1 LAST COMMENT_BODY TRUE
R 1
J 0
(-8475 2075);
DISPLAY 0.872340 (-8475 2075);
PAINT PEACH (-8475 2075);
DISPLAY INVISIBLE (-8475 2075);
FORCEADD QUANTA_TITLE_BLOCK_C..1
(-100 100);
FORCEPROP 0 LAST CDS_CON_LAST_MODIFIED Thu Sep 14 16:12:10 2023
J 0
(-1985 115);
DISPLAY INVISIBLE (-1985 115);
FORCEPROP 1 LAST CUSTOM_TXT_CDS <CON_LAST_MODIFIED>
J 0
(-1985 115);
DISPLAY 0.978723 (-1985 115);
FORCEPROP 2 LAST CUSTOM_TXT_CDS <XR_PAGE_TITLE>
J 0
(-7990 5350);
DISPLAY 0.638298 (-7990 5350);
PAINT PINK (-7990 5350);
DISPLAY INVISIBLE (-7990 5350);
FORCEPROP 1 LAST CUSTOM_TXT_CDS <NAME_2>
J 0
(-3275 150);
FORCEPROP 1 LAST CUSTOM_TXT_CDS <NAME_1>
J 0
(-3275 275);
FORCEPROP 1 LAST CUSTOM_TXT_CDS <Q_NUMBER>
J 0
(-1503 203);
DISPLAY 1.212766 (-1503 203);
FORCEPROP 1 LAST CUSTOM_TXT_CDS <Q_PROJ>
J 0
(-2482 202);
DISPLAY 1.212766 (-2482 202);
FORCEPROP 1 LAST CUSTOM_TXT_CDS <Q_REV>
J 0
(-284 203);
DISPLAY 1.212766 (-284 203);
FORCEPROP 1 LAST CUSTOM_TXT_CDS <CON_PAGE_NUM> OF <CON_TOTAL_PAGES>
J 0
(-546 118);
DISPLAY 0.978723 (-546 118);
FORCEPROP 1 LAST Q_TITLE DDR5 - CPU1 CHC
J 0
(-9425 125);
DISPLAY 2.446809 (-9425 125);
PAINT GREEN (-9425 125);
FORCEPROP 2 LAST PAGE_BORDER TRUE
J 0
(-7990 5350);
DISPLAY 0.638298 (-7990 5350);
PAINT PINK (-7990 5350);
DISPLAY INVISIBLE (-7990 5350);
FORCEPROP 2 LAST CDS_LIB pure_quanta
J 0
(-100 100);
DISPLAY INVISIBLE (-100 100);
FORCEPROP 1 LAST CDS_LMAN_SYM_OUTLINE -9475,6775,100,-125
J 0
(-100 100);
DISPLAY 0.468085 (-100 100);
PAINT GREEN (-100 100);
DISPLAY INVISIBLE (-100 100);
FORCEPROP 2 LAST CDS_XR_PAGE_TITLE CR-100 : @T6G_MB_LIB.T6G(SCH_1):PAGE100
J 0
(-7990 5350);
DISPLAY 0.638298 (-7990 5350);
PAINT PINK (-7990 5350);
DISPLAY INVISIBLE (-7990 5350);
FORCEPROP 1 LAST Q_DEPT BU9
J 1
(-3863 149);
DISPLAY 1.957447 (-3863 149);
PAINT GREEN (-3863 149);
DISPLAY INVISIBLE (-3863 149);
FORCEPROP 1 LAST COMMENT_BODY TRUE
J 0
(-88 87);
DISPLAY 0.978723 (-88 87);
PAINT GREEN (-88 87);
DISPLAY INVISIBLE (-88 87);
WIRE 17 -1 (-3500 3550)(-3500 3525);
WIRE 17 -1 (-3500 3550)(-2600 3550);
FORCEPROP 2 LAST SIG_NAME M_C_CPU1_SB_DQS_DP<9:0>
J 0
(-3235 3560);
DISPLAY 0.489362 (-3235 3560);
WIRE 17 -1 (-3300 3500)(-3300 3475);
WIRE 17 -1 (-3300 3500)(-2600 3500);
FORCEPROP 2 LAST SIG_NAME M_C_CPU1_SB_DQS_DN<9:0>
J 0
(-3235 3510);
DISPLAY 0.489362 (-3235 3510);
WIRE 17 -1 (-3500 4600)(-3500 4575);
WIRE 17 -1 (-3500 4600)(-2600 4600);
FORCEPROP 2 LAST SIG_NAME M_C_CPU1_SA_DQS_DP<9:0>
J 0
(-3235 4610);
DISPLAY 0.489362 (-3235 4610);
WIRE 17 -1 (-3300 4550)(-3300 4525);
WIRE 17 -1 (-3300 4550)(-2600 4550);
FORCEPROP 2 LAST SIG_NAME M_C_CPU1_SA_DQS_DN<9:0>
J 0
(-3235 4560);
DISPLAY 0.489362 (-3235 4560);
WIRE 17 -1 (-3500 4575)(-3500 4475);
WIRE 17 -1 (-3500 4475)(-3500 4375);
WIRE 17 -1 (-3500 4375)(-3500 4275);
WIRE 17 -1 (-3300 4525)(-3300 4425);
WIRE 17 -1 (-3300 4425)(-3300 4325);
WIRE 17 -1 (-3300 4325)(-3300 4225);
WIRE 17 -1 (-3300 3375)(-3300 3275);
WIRE 17 -1 (-3300 3475)(-3300 3375);
WIRE 17 -1 (-3300 3275)(-3300 3175);
WIRE 17 -1 (-3300 3175)(-3300 3075);
WIRE 17 -1 (-3500 4275)(-3500 4175);
WIRE 17 -1 (-3500 3325)(-3500 3225);
WIRE 17 -1 (-3500 3425)(-3500 3325);
WIRE 17 -1 (-3500 3225)(-3500 3125);
WIRE 17 -1 (-3500 3025)(-3500 3125);
WIRE 17 -1 (-3500 3525)(-3500 3425);
WIRE 17 -1 (-3500 2925)(-3500 3025);
WIRE 17 -1 (-3500 2825)(-3500 2925);
WIRE 17 -1 (-3300 2975)(-3300 3075);
WIRE 17 -1 (-3300 2875)(-3300 2975);
WIRE 17 -1 (-3300 2775)(-3300 2875);
WIRE 17 -1 (-3300 4225)(-3300 4125);
WIRE 17 -1 (-3300 4025)(-3300 4125);
WIRE 17 -1 (-3300 3925)(-3300 4025);
WIRE 17 -1 (-3300 3825)(-3300 3925);
WIRE 17 -1 (-3500 2825)(-3500 2725);
WIRE 17 -1 (-3300 2775)(-3300 2675);
WIRE 17 -1 (-3500 4075)(-3500 4175);
WIRE 17 -1 (-3500 3975)(-3500 4075);
WIRE 17 -1 (-3500 3875)(-3500 3975);
WIRE 17 -1 (-3500 3875)(-3500 3775);
WIRE 17 -1 (-3300 3825)(-3300 3725);
WIRE 17 -1 (-3500 2725)(-3500 2625);
WIRE 17 -1 (-3300 2675)(-3300 2575);
WIRE 17 -1 (-3500 3775)(-3500 3675);
WIRE 17 -1 (-3300 3725)(-3300 3625);
WIRE 17 -1 (-6150 2225)(-6150 2275);
WIRE 17 -1 (-6150 2275)(-6150 2325);
WIRE 17 -1 (-6150 2325)(-6150 2375);
WIRE 17 -1 (-6150 2375)(-6150 2425);
WIRE 17 -1 (-6150 2475)(-6150 2425);
WIRE 17 -1 (-6150 2525)(-6150 2475);
WIRE 17 -1 (-6150 2575)(-6150 2525);
WIRE 17 -1 (-6150 2625)(-6150 2575);
WIRE 17 -1 (-6150 2675)(-6150 2625);
WIRE 17 -1 (-6150 2725)(-6150 2675);
WIRE 17 -1 (-6150 2775)(-6150 2725);
WIRE 17 -1 (-6150 2825)(-6150 2775);
WIRE 17 -1 (-6150 2825)(-6150 2875);
WIRE 17 -1 (-6150 2875)(-6150 2925);
WIRE 17 -1 (-6150 2925)(-6150 2975);
WIRE 17 -1 (-6150 2975)(-6150 3025);
WIRE 17 -1 (-6150 3075)(-6150 3025);
WIRE 17 -1 (-6150 3125)(-6150 3075);
WIRE 17 -1 (-6150 3175)(-6150 3125);
WIRE 17 -1 (-6150 3225)(-6150 3175);
WIRE 17 -1 (-6150 3275)(-6150 3225);
WIRE 17 -1 (-6150 3325)(-6150 3275);
WIRE 17 -1 (-6150 3375)(-6150 3325);
WIRE 17 -1 (-6150 3425)(-6150 3375);
WIRE 17 -1 (-6150 3475)(-6150 3425);
WIRE 17 -1 (-6150 3525)(-6150 3475);
WIRE 17 -1 (-6150 3575)(-6150 3525);
WIRE 17 -1 (-6150 3625)(-6150 3575);
WIRE 17 -1 (-6150 3675)(-6150 3625);
WIRE 17 -1 (-6150 3725)(-6150 3675);
WIRE 17 -1 (-6150 3775)(-6150 3725);
WIRE 17 -1 (-6150 3800)(-6150 3775);
WIRE 17 -1 (-6150 3800)(-5650 3800);
FORCEPROP 2 LAST SIG_NAME M_C_CPU1_SB_DQ<31:0>
J 2
(-5650 3810);
DISPLAY 0.489362 (-5650 3810);
WIRE 17 -1 (-6150 3875)(-6150 3925);
WIRE 17 -1 (-6150 3925)(-6150 3975);
WIRE 17 -1 (-6150 3975)(-6150 4025);
WIRE 17 -1 (-6150 4025)(-6150 4075);
WIRE 17 -1 (-6150 4125)(-6150 4075);
WIRE 17 -1 (-6150 4175)(-6150 4125);
WIRE 17 -1 (-6150 4225)(-6150 4175);
WIRE 17 -1 (-6150 4275)(-6150 4225);
WIRE 17 -1 (-6150 4325)(-6150 4275);
WIRE 17 -1 (-6150 4375)(-6150 4325);
WIRE 17 -1 (-6150 4425)(-6150 4375);
WIRE 17 -1 (-6150 4475)(-6150 4425);
WIRE 17 -1 (-6150 4475)(-6150 4525);
WIRE 17 -1 (-6150 4525)(-6150 4575);
WIRE 17 -1 (-6150 4575)(-6150 4625);
WIRE 17 -1 (-6150 4625)(-6150 4675);
WIRE 17 -1 (-6150 4725)(-6150 4675);
WIRE 17 -1 (-6150 4775)(-6150 4725);
WIRE 17 -1 (-6150 4825)(-6150 4775);
WIRE 17 -1 (-6150 4875)(-6150 4825);
WIRE 17 -1 (-6150 4925)(-6150 4875);
WIRE 17 -1 (-6150 4975)(-6150 4925);
WIRE 17 -1 (-6150 5025)(-6150 4975);
WIRE 17 -1 (-6150 5075)(-6150 5025);
WIRE 17 -1 (-6150 5125)(-6150 5075);
WIRE 17 -1 (-6150 5175)(-6150 5125);
WIRE 17 -1 (-6150 5225)(-6150 5175);
WIRE 17 -1 (-6150 5275)(-6150 5225);
WIRE 17 -1 (-6150 5325)(-6150 5275);
WIRE 17 -1 (-6150 5375)(-6150 5325);
WIRE 17 -1 (-6150 5425)(-6150 5375);
WIRE 17 -1 (-6150 5450)(-6150 5425);
WIRE 17 -1 (-6150 5450)(-5650 5450);
FORCEPROP 2 LAST SIG_NAME M_C_CPU1_SA_DQ<31:0>
J 2
(-5650 5460);
DISPLAY 0.489362 (-5650 5460);
WIRE 17 -1 (-7950 3225)(-7950 3275);
WIRE 17 -1 (-7950 3275)(-7950 3325);
WIRE 17 -1 (-7950 3325)(-7950 3375);
WIRE 17 -1 (-7950 3375)(-7950 3425);
WIRE 17 -1 (-7950 3475)(-7950 3425);
WIRE 17 -1 (-7950 3475)(-7950 3525);
WIRE 17 -1 (-7950 3575)(-7950 3525);
WIRE 17 -1 (-7950 3575)(-7950 3600);
WIRE 17 -1 (-7950 3600)(-8450 3600);
FORCEPROP 2 LAST SIG_NAME M_C_CPU1_SB_CB<7:0>
J 0
(-8450 3610);
DISPLAY 0.489362 (-8450 3610);
WIRE 17 -1 (-7950 3675)(-7950 3725);
WIRE 17 -1 (-7950 3725)(-7950 3775);
WIRE 17 -1 (-7950 3775)(-7950 3825);
WIRE 17 -1 (-7950 3825)(-7950 3875);
WIRE 17 -1 (-7950 3925)(-7950 3875);
WIRE 17 -1 (-7950 3925)(-7950 3975);
WIRE 17 -1 (-7950 4025)(-7950 3975);
WIRE 17 -1 (-7950 4025)(-7950 4050);
WIRE 17 -1 (-7950 4050)(-8450 4050);
FORCEPROP 2 LAST SIG_NAME M_C_CPU1_SA_CB<7:0>
J 0
(-8450 4060);
DISPLAY 0.489362 (-8450 4060);
WIRE 17 -1 (-7950 5025)(-7950 5050);
WIRE 17 -1 (-7950 4975)(-7950 5025);
WIRE 17 -1 (-7950 5050)(-8450 5050);
FORCEPROP 2 LAST SIG_NAME M_C_CPU1_SB_CA<6:0>
J 0
(-8450 5060);
DISPLAY 0.489362 (-8450 5060);
WIRE 17 -1 (-7950 5425)(-7950 5450);
WIRE 17 -1 (-7950 5375)(-7950 5425);
WIRE 17 -1 (-7950 5450)(-8450 5450);
FORCEPROP 2 LAST SIG_NAME M_C_CPU1_SA_CA<6:0>
J 0
(-8450 5460);
DISPLAY 0.489362 (-8450 5460);
WIRE 17 -1 (-7950 4925)(-7950 4975);
WIRE 17 -1 (-7950 5325)(-7950 5375);
WIRE 17 -1 (-7950 4875)(-7950 4925);
WIRE 17 -1 (-7950 4825)(-7950 4875);
WIRE 17 -1 (-7950 4775)(-7950 4825);
WIRE 17 -1 (-7950 5275)(-7950 5325);
WIRE 17 -1 (-7950 5225)(-7950 5275);
WIRE 17 -1 (-7950 5175)(-7950 5225);
WIRE 17 -1 (-7950 4725)(-7950 4775);
WIRE 17 -1 (-7950 5125)(-7950 5175);
WIRE 16 -1 (-6600 1075)(-6600 1150);
WIRE 16 -1 (-8775 3050)(-8775 3125);
WIRE 16 -1 (-8575 2400)(-8575 2425);
WIRE 16 -1 (-6450 5400)(-6250 5400);
WIRE 16 -1 (-7650 4000)(-7850 4000);
WIRE 16 -1 (-7650 3850)(-7850 3850);
WIRE 16 -1 (-7650 3700)(-7850 3700);
WIRE 16 -1 (-7650 3550)(-7850 3550);
WIRE 16 -1 (-7650 5100)(-7850 5100);
WIRE 16 -1 (-7650 4700)(-7850 4700);
WIRE 16 -1 (-7650 5150)(-7850 5150);
WIRE 16 -1 (-7650 4750)(-7850 4750);
WIRE 16 -1 (-7650 5200)(-7850 5200);
WIRE 16 -1 (-7650 4800)(-7850 4800);
WIRE 16 -1 (-7650 5250)(-7850 5250);
WIRE 16 -1 (-7650 4850)(-7850 4850);
WIRE 16 -1 (-7650 5300)(-7850 5300);
WIRE 16 -1 (-7650 4900)(-7850 4900);
WIRE 16 -1 (-7650 5350)(-7850 5350);
WIRE 16 -1 (-7650 4950)(-7850 4950);
WIRE 16 -1 (-7650 5400)(-7850 5400);
WIRE 16 -1 (-7650 5000)(-7850 5000);
WIRE 16 -1 (-7650 3950)(-7850 3950);
WIRE 16 -1 (-7650 3900)(-7850 3900);
WIRE 16 -1 (-7650 3800)(-7850 3800);
WIRE 16 -1 (-7650 3750)(-7850 3750);
WIRE 16 -1 (-7650 3650)(-7850 3650);
WIRE 16 -1 (-7650 3500)(-7850 3500);
WIRE 16 -1 (-7650 3450)(-7850 3450);
WIRE 16 -1 (-7650 3400)(-7850 3400);
WIRE 16 -1 (-7650 3350)(-7850 3350);
WIRE 16 -1 (-7650 3300)(-7850 3300);
WIRE 16 -1 (-7650 3250)(-7850 3250);
WIRE 16 -1 (-7650 3200)(-7850 3200);
WIRE 16 -1 (-7650 4150)(-8450 4150);
FORCEPROP 2 LAST SIG_NAME M_C_CPU1_CLK_DP<0>
J 0
(-8450 4160);
DISPLAY 0.489362 (-8450 4160);
WIRE 16 -1 (-7650 4250)(-8450 4250);
FORCEPROP 2 LAST SIG_NAME M_C_CPU1_SB_CS_N<0>
J 0
(-8450 4260);
DISPLAY 0.489362 (-8450 4260);
WIRE 16 -1 (-7650 4450)(-8450 4450);
FORCEPROP 2 LAST SIG_NAME M_C_CPU1_SA_CS_N<1>
J 0
(-8450 4460);
DISPLAY 0.489362 (-8450 4460);
WIRE 16 -1 (-7650 4300)(-8450 4300);
FORCEPROP 2 LAST SIG_NAME M_C_CPU1_SB_CS_N<1>
J 0
(-8450 4310);
DISPLAY 0.489362 (-8450 4310);
WIRE 16 -1 (-6250 5350)(-6450 5350);
WIRE 16 -1 (-6250 5300)(-6450 5300);
WIRE 16 -1 (-6250 5250)(-6450 5250);
WIRE 16 -1 (-6450 5200)(-6250 5200);
WIRE 16 -1 (-6250 5150)(-6450 5150);
WIRE 16 -1 (-6250 5100)(-6450 5100);
WIRE 16 -1 (-6250 5050)(-6450 5050);
WIRE 16 -1 (-6450 5000)(-6250 5000);
WIRE 16 -1 (-6250 4950)(-6450 4950);
WIRE 16 -1 (-6250 4900)(-6450 4900);
WIRE 16 -1 (-6250 4850)(-6450 4850);
WIRE 16 -1 (-6450 4800)(-6250 4800);
WIRE 16 -1 (-6250 4750)(-6450 4750);
WIRE 16 -1 (-6250 4700)(-6450 4700);
WIRE 16 -1 (-6250 4650)(-6450 4650);
WIRE 16 -1 (-6450 4600)(-6250 4600);
WIRE 16 -1 (-6250 4550)(-6450 4550);
WIRE 16 -1 (-6250 4500)(-6450 4500);
WIRE 16 -1 (-6250 4450)(-6450 4450);
WIRE 16 -1 (-6450 4400)(-6250 4400);
WIRE 16 -1 (-6250 4350)(-6450 4350);
WIRE 16 -1 (-6250 4300)(-6450 4300);
WIRE 16 -1 (-6250 4250)(-6450 4250);
WIRE 16 -1 (-6450 4200)(-6250 4200);
WIRE 16 -1 (-6250 4150)(-6450 4150);
WIRE 16 -1 (-6250 4100)(-6450 4100);
WIRE 16 -1 (-6250 4050)(-6450 4050);
WIRE 16 -1 (-6450 4000)(-6250 4000);
WIRE 16 -1 (-6250 3950)(-6450 3950);
WIRE 16 -1 (-6250 3900)(-6450 3900);
WIRE 16 -1 (-6250 3850)(-6450 3850);
WIRE 16 -1 (-6450 3750)(-6250 3750);
WIRE 16 -1 (-6250 3700)(-6450 3700);
WIRE 16 -1 (-6250 3650)(-6450 3650);
WIRE 16 -1 (-6250 3600)(-6450 3600);
WIRE 16 -1 (-6450 3550)(-6250 3550);
WIRE 16 -1 (-6250 3500)(-6450 3500);
WIRE 16 -1 (-6250 3450)(-6450 3450);
WIRE 16 -1 (-6250 3400)(-6450 3400);
WIRE 16 -1 (-6450 3350)(-6250 3350);
WIRE 16 -1 (-6250 3300)(-6450 3300);
WIRE 16 -1 (-6250 3250)(-6450 3250);
WIRE 16 -1 (-6250 3200)(-6450 3200);
WIRE 16 -1 (-6450 3150)(-6250 3150);
WIRE 16 -1 (-6250 3100)(-6450 3100);
WIRE 16 -1 (-6250 3050)(-6450 3050);
WIRE 16 -1 (-6250 3000)(-6450 3000);
WIRE 16 -1 (-6450 2950)(-6250 2950);
WIRE 16 -1 (-6250 2900)(-6450 2900);
WIRE 16 -1 (-6250 2850)(-6450 2850);
WIRE 16 -1 (-6250 2800)(-6450 2800);
WIRE 16 -1 (-6450 2750)(-6250 2750);
WIRE 16 -1 (-6250 2700)(-6450 2700);
WIRE 16 -1 (-6250 2650)(-6450 2650);
WIRE 16 -1 (-6250 2600)(-6450 2600);
WIRE 16 -1 (-6450 2550)(-6250 2550);
WIRE 16 -1 (-6250 2500)(-6450 2500);
WIRE 16 -1 (-6250 2450)(-6450 2450);
WIRE 16 -1 (-6250 2400)(-6450 2400);
WIRE 16 -1 (-6450 2350)(-6250 2350);
WIRE 16 -1 (-6250 2300)(-6450 2300);
WIRE 16 -1 (-6250 2250)(-6450 2250);
WIRE 16 -1 (-6250 2200)(-6450 2200);
WIRE 16 -1 (-7650 2000)(-8450 2000);
FORCEPROP 2 LAST SIG_NAME M_C_CPU1_SA_RSP<0>
J 0
(-8450 2010);
DISPLAY 0.489362 (-8450 2010);
WIRE 16 -1 (-7650 1950)(-8450 1950);
FORCEPROP 2 LAST SIG_NAME M_C_CPU1_SB_RSP<0>
J 0
(-8450 1960);
DISPLAY 0.489362 (-8450 1960);
WIRE 16 -1 (-7650 4600)(-8450 4600);
FORCEPROP 2 LAST SIG_NAME M_C_CPU1_SA_PAR
J 0
(-8450 4610);
DISPLAY 0.489362 (-8450 4610);
WIRE 16 -1 (-3750 4300)(-3400 4300);
WIRE 16 -1 (-3600 4250)(-3750 4250);
WIRE 16 -1 (-3600 3400)(-3750 3400);
WIRE 16 -1 (-3750 3350)(-3400 3350);
WIRE 16 -1 (-3600 3300)(-3750 3300);
WIRE 16 -1 (-3750 3600)(-3400 3600);
WIRE 16 -1 (-3600 3650)(-3750 3650);
WIRE 16 -1 (-3750 2550)(-3400 2550);
WIRE 16 -1 (-3600 2600)(-3750 2600);
WIRE 16 -1 (-3750 3700)(-3400 3700);
WIRE 16 -1 (-3750 3750)(-3600 3750);
WIRE 16 -1 (-3750 2650)(-3400 2650);
WIRE 16 -1 (-3750 2700)(-3600 2700);
WIRE 16 -1 (-3750 3800)(-3400 3800);
WIRE 16 -1 (-3600 3850)(-3750 3850);
WIRE 16 -1 (-3750 2750)(-3400 2750);
WIRE 16 -1 (-3600 2800)(-3750 2800);
WIRE 16 -1 (-3400 3900)(-3750 3900);
WIRE 16 -1 (-3600 3950)(-3750 3950);
WIRE 16 -1 (-3750 2850)(-3400 2850);
WIRE 16 -1 (-3600 2900)(-3750 2900);
WIRE 16 -1 (-3750 4000)(-3400 4000);
WIRE 16 -1 (-3600 4050)(-3750 4050);
WIRE 16 -1 (-3750 2950)(-3400 2950);
WIRE 16 -1 (-3600 3000)(-3750 3000);
WIRE 16 -1 (-3400 4100)(-3750 4100);
WIRE 16 -1 (-3750 4150)(-3600 4150);
WIRE 16 -1 (-3750 3050)(-3400 3050);
WIRE 16 -1 (-3750 3100)(-3600 3100);
WIRE 16 -1 (-3750 4200)(-3400 4200);
WIRE 16 -1 (-3750 3150)(-3400 3150);
WIRE 16 -1 (-3600 3200)(-3750 3200);
WIRE 16 -1 (-3600 4350)(-3750 4350);
WIRE 16 -1 (-3750 3250)(-3400 3250);
WIRE 16 -1 (-3750 4400)(-3400 4400);
WIRE 16 -1 (-3600 4450)(-3750 4450);
WIRE 16 -1 (-3750 4500)(-3400 4500);
WIRE 16 -1 (-3750 4550)(-3600 4550);
WIRE 16 -1 (-3750 3450)(-3400 3450);
WIRE 16 -1 (-3750 3500)(-3600 3500);
WIRE 16 -1 (-7650 4100)(-8450 4100);
FORCEPROP 2 LAST SIG_NAME M_C_CPU1_CLK_DN<0>
J 0
(-8450 4110);
DISPLAY 0.489362 (-8450 4110);
WIRE 16 -1 (-6600 1425)(-6600 1350);
WIRE 16 -1 (-6600 1425)(-7325 1425);
FORCEPROP 2 LAST SIG_NAME PD_CHC_CPU1_DIMM_SAA
J 0
(-7310 1435);
DISPLAY 0.489362 (-7310 1435);
WIRE 16 -1 (-9150 2150)(-8800 2150);
FORCEPROP 2 LAST SIG_NAME PWRGD_CHAF_CPU1
J 0
(-9160 2160);
DISPLAY 0.489362 (-9160 2160);
WIRE 16 -1 (-7650 4550)(-8450 4550);
FORCEPROP 2 LAST SIG_NAME M_C_CPU1_SB_PAR
J 0
(-8450 4560);
DISPLAY 0.489362 (-8450 4560);
WIRE 16 -1 (-7650 4400)(-8450 4400);
FORCEPROP 2 LAST SIG_NAME M_C_CPU1_SA_CS_N<0>
J 0
(-8450 4410);
DISPLAY 0.489362 (-8450 4410);
WIRE 16 -1 (-7650 3100)(-8275 3100);
FORCEPROP 2 LAST SIG_NAME M_C_CPU1_RESET_N
J 0
(-8275 3110);
DISPLAY 0.489362 (-8275 3110);
WIRE 16 -1 (-2350 6075)(-2225 6075);
WIRE 16 -1 (-2350 6075)(-2350 5975);
WIRE 16 -1 (-2350 6075)(-2925 6075);
WIRE 16 -1 (-2225 5400)(-2225 6075);
WIRE 16 -1 (-1925 5400)(-2225 5400);
WIRE 16 -1 (-2225 5350)(-2225 5400);
WIRE 16 -1 (-2925 5975)(-2925 6075);
WIRE 16 -1 (-2925 6075)(-2925 6150);
WIRE 16 -1 (-1925 5350)(-2225 5350);
WIRE 16 -1 (-2225 5300)(-2225 5350);
WIRE 16 -1 (-1925 5300)(-2225 5300);
WIRE 16 -1 (-2350 5650)(-2350 5775);
WIRE 16 -1 (-2350 5650)(-2925 5650);
WIRE 16 -1 (-2925 5650)(-2925 5775);
WIRE 16 -1 (-2925 5650)(-2925 5575);
WIRE 16 -1 (-425 2250)(-425 2150);
WIRE 16 -1 (-425 2300)(-425 2250);
WIRE 16 -1 (-425 2250)(-725 2250);
WIRE 16 -1 (-425 2150)(-425 2100);
WIRE 16 -1 (-425 2150)(-725 2150);
WIRE 16 -1 (-425 2100)(-425 2050);
WIRE 16 -1 (-425 2100)(-725 2100);
WIRE 16 -1 (-425 2350)(-425 2300);
WIRE 16 -1 (-425 2300)(-725 2300);
WIRE 16 -1 (-425 2400)(-425 2350);
WIRE 16 -1 (-425 2350)(-725 2350);
WIRE 16 -1 (-425 2050)(-725 2050);
WIRE 16 -1 (-425 2050)(-425 1850);
WIRE 16 -1 (-425 2450)(-425 2400);
WIRE 16 -1 (-425 2400)(-725 2400);
WIRE 16 -1 (-425 2500)(-425 2450);
WIRE 16 -1 (-425 2450)(-725 2450);
WIRE 16 -1 (-425 2550)(-425 2500);
WIRE 16 -1 (-425 2500)(-725 2500);
WIRE 16 -1 (-425 2600)(-425 2550);
WIRE 16 -1 (-425 2550)(-725 2550);
WIRE 16 -1 (-425 2650)(-425 2600);
WIRE 16 -1 (-425 2600)(-725 2600);
WIRE 16 -1 (-425 2700)(-425 2650);
WIRE 16 -1 (-425 2650)(-725 2650);
WIRE 16 -1 (-425 2750)(-425 2700);
WIRE 16 -1 (-425 2700)(-725 2700);
WIRE 16 -1 (-425 2800)(-425 2750);
WIRE 16 -1 (-425 2750)(-725 2750);
WIRE 16 -1 (-425 2850)(-425 2800);
WIRE 16 -1 (-425 2800)(-725 2800);
WIRE 16 -1 (-425 2900)(-425 2850);
WIRE 16 -1 (-425 2850)(-725 2850);
WIRE 16 -1 (-425 2950)(-425 2900);
WIRE 16 -1 (-425 2900)(-725 2900);
WIRE 16 -1 (-425 3000)(-425 2950);
WIRE 16 -1 (-425 2950)(-725 2950);
WIRE 16 -1 (-425 3050)(-425 3000);
WIRE 16 -1 (-425 3000)(-725 3000);
WIRE 16 -1 (-425 3100)(-425 3050);
WIRE 16 -1 (-425 3050)(-725 3050);
WIRE 16 -1 (-425 3150)(-425 3100);
WIRE 16 -1 (-425 3100)(-725 3100);
WIRE 16 -1 (-425 3200)(-425 3150);
WIRE 16 -1 (-425 3150)(-725 3150);
WIRE 16 -1 (-425 3250)(-425 3200);
WIRE 16 -1 (-425 3200)(-725 3200);
WIRE 16 -1 (-425 3300)(-425 3250);
WIRE 16 -1 (-425 3250)(-725 3250);
WIRE 16 -1 (-425 3350)(-425 3300);
WIRE 16 -1 (-425 3300)(-725 3300);
WIRE 16 -1 (-425 3400)(-425 3350);
WIRE 16 -1 (-425 3350)(-725 3350);
WIRE 16 -1 (-425 3450)(-425 3400);
WIRE 16 -1 (-425 3400)(-725 3400);
WIRE 16 -1 (-425 3500)(-425 3450);
WIRE 16 -1 (-425 3450)(-725 3450);
WIRE 16 -1 (-425 3550)(-425 3500);
WIRE 16 -1 (-425 3500)(-725 3500);
WIRE 16 -1 (-425 3600)(-425 3550);
WIRE 16 -1 (-425 3550)(-725 3550);
WIRE 16 -1 (-425 3650)(-425 3600);
WIRE 16 -1 (-425 3600)(-725 3600);
WIRE 16 -1 (-425 3700)(-425 3650);
WIRE 16 -1 (-425 3650)(-725 3650);
WIRE 16 -1 (-425 3750)(-425 3700);
WIRE 16 -1 (-425 3700)(-725 3700);
WIRE 16 -1 (-425 3800)(-425 3750);
WIRE 16 -1 (-425 3750)(-725 3750);
WIRE 16 -1 (-425 3850)(-425 3800);
WIRE 16 -1 (-425 3800)(-725 3800);
WIRE 16 -1 (-425 3900)(-425 3850);
WIRE 16 -1 (-425 3850)(-725 3850);
WIRE 16 -1 (-425 3950)(-425 3900);
WIRE 16 -1 (-425 3900)(-725 3900);
WIRE 16 -1 (-425 4000)(-425 3950);
WIRE 16 -1 (-425 3950)(-725 3950);
WIRE 16 -1 (-425 4050)(-425 4000);
WIRE 16 -1 (-425 4000)(-725 4000);
WIRE 16 -1 (-425 4100)(-425 4050);
WIRE 16 -1 (-425 4050)(-725 4050);
WIRE 16 -1 (-425 4150)(-425 4100);
WIRE 16 -1 (-425 4100)(-725 4100);
WIRE 16 -1 (-425 4200)(-425 4150);
WIRE 16 -1 (-425 4150)(-725 4150);
WIRE 16 -1 (-425 4250)(-425 4200);
WIRE 16 -1 (-425 4200)(-725 4200);
WIRE 16 -1 (-425 4300)(-425 4250);
WIRE 16 -1 (-425 4250)(-725 4250);
WIRE 16 -1 (-425 4350)(-425 4300);
WIRE 16 -1 (-425 4300)(-725 4300);
WIRE 16 -1 (-425 4400)(-425 4350);
WIRE 16 -1 (-425 4350)(-725 4350);
WIRE 16 -1 (-425 4450)(-425 4400);
WIRE 16 -1 (-425 4400)(-725 4400);
WIRE 16 -1 (-425 4500)(-425 4450);
WIRE 16 -1 (-425 4450)(-725 4450);
WIRE 16 -1 (-425 4550)(-425 4500);
WIRE 16 -1 (-425 4500)(-725 4500);
WIRE 16 -1 (-425 4600)(-425 4550);
WIRE 16 -1 (-425 4550)(-725 4550);
WIRE 16 -1 (-425 4650)(-425 4600);
WIRE 16 -1 (-425 4600)(-725 4600);
WIRE 16 -1 (-425 4700)(-425 4650);
WIRE 16 -1 (-425 4650)(-725 4650);
WIRE 16 -1 (-425 4750)(-425 4700);
WIRE 16 -1 (-425 4700)(-725 4700);
WIRE 16 -1 (-425 4800)(-425 4750);
WIRE 16 -1 (-425 4750)(-725 4750);
WIRE 16 -1 (-425 4850)(-425 4800);
WIRE 16 -1 (-425 4800)(-725 4800);
WIRE 16 -1 (-425 4900)(-425 4850);
WIRE 16 -1 (-425 4850)(-725 4850);
WIRE 16 -1 (-425 4950)(-425 4900);
WIRE 16 -1 (-425 4900)(-725 4900);
WIRE 16 -1 (-425 5000)(-425 4950);
WIRE 16 -1 (-425 4950)(-725 4950);
WIRE 16 -1 (-425 5050)(-425 5000);
WIRE 16 -1 (-425 5000)(-725 5000);
WIRE 16 -1 (-425 5100)(-425 5050);
WIRE 16 -1 (-425 5050)(-725 5050);
WIRE 16 -1 (-425 5150)(-425 5100);
WIRE 16 -1 (-425 5100)(-725 5100);
WIRE 16 -1 (-425 5200)(-425 5150);
WIRE 16 -1 (-425 5150)(-725 5150);
WIRE 16 -1 (-425 5250)(-425 5200);
WIRE 16 -1 (-425 5200)(-725 5200);
WIRE 16 -1 (-425 5300)(-425 5250);
WIRE 16 -1 (-425 5250)(-725 5250);
WIRE 16 -1 (-425 5350)(-425 5300);
WIRE 16 -1 (-425 5300)(-725 5300);
WIRE 16 -1 (-425 5400)(-425 5350);
WIRE 16 -1 (-425 5350)(-725 5350);
WIRE 16 -1 (-425 5400)(-725 5400);
WIRE 16 -1 (-1925 2200)(-2225 2200);
WIRE 16 -1 (-2225 2250)(-2225 2200);
WIRE 16 -1 (-2225 2200)(-2225 2150);
WIRE 16 -1 (-1925 2150)(-2225 2150);
WIRE 16 -1 (-2225 2150)(-2225 2050);
WIRE 16 -1 (-1925 2250)(-2225 2250);
WIRE 16 -1 (-2225 2300)(-2225 2250);
WIRE 16 -1 (-1925 2300)(-2225 2300);
WIRE 16 -1 (-2225 2350)(-2225 2300);
WIRE 16 -1 (-1925 2350)(-2225 2350);
WIRE 16 -1 (-2225 2400)(-2225 2350);
WIRE 16 -1 (-1925 2400)(-2225 2400);
WIRE 16 -1 (-2225 2450)(-2225 2400);
WIRE 16 -1 (-1925 2450)(-2225 2450);
WIRE 16 -1 (-2225 2500)(-2225 2450);
WIRE 16 -1 (-1925 2500)(-2225 2500);
WIRE 16 -1 (-2225 2550)(-2225 2500);
WIRE 16 -1 (-1925 2550)(-2225 2550);
WIRE 16 -1 (-2225 2600)(-2225 2550);
WIRE 16 -1 (-1925 2600)(-2225 2600);
WIRE 16 -1 (-2225 2650)(-2225 2600);
WIRE 16 -1 (-1925 2650)(-2225 2650);
WIRE 16 -1 (-2225 2700)(-2225 2650);
WIRE 16 -1 (-1925 2700)(-2225 2700);
WIRE 16 -1 (-2225 2750)(-2225 2700);
WIRE 16 -1 (-1925 2750)(-2225 2750);
WIRE 16 -1 (-2225 2800)(-2225 2750);
WIRE 16 -1 (-1925 2800)(-2225 2800);
WIRE 16 -1 (-2225 2850)(-2225 2800);
WIRE 16 -1 (-1925 2850)(-2225 2850);
WIRE 16 -1 (-2225 2900)(-2225 2850);
WIRE 16 -1 (-1925 2900)(-2225 2900);
WIRE 16 -1 (-2225 2950)(-2225 2900);
WIRE 16 -1 (-1925 2950)(-2225 2950);
WIRE 16 -1 (-2225 3000)(-2225 2950);
WIRE 16 -1 (-1925 3000)(-2225 3000);
WIRE 16 -1 (-2225 3050)(-2225 3000);
WIRE 16 -1 (-1925 3050)(-2225 3050);
WIRE 16 -1 (-2225 3100)(-2225 3050);
WIRE 16 -1 (-1925 3100)(-2225 3100);
WIRE 16 -1 (-2225 3150)(-2225 3100);
WIRE 16 -1 (-1925 3150)(-2225 3150);
WIRE 16 -1 (-2225 3200)(-2225 3150);
WIRE 16 -1 (-1925 3200)(-2225 3200);
WIRE 16 -1 (-2225 3250)(-2225 3200);
WIRE 16 -1 (-1925 3250)(-2225 3250);
WIRE 16 -1 (-2225 3300)(-2225 3250);
WIRE 16 -1 (-1925 3300)(-2225 3300);
WIRE 16 -1 (-2225 3350)(-2225 3300);
WIRE 16 -1 (-1925 3350)(-2225 3350);
WIRE 16 -1 (-2225 3400)(-2225 3350);
WIRE 16 -1 (-1925 3400)(-2225 3400);
WIRE 16 -1 (-2225 3450)(-2225 3400);
WIRE 16 -1 (-1925 3450)(-2225 3450);
WIRE 16 -1 (-2225 3500)(-2225 3450);
WIRE 16 -1 (-1925 3500)(-2225 3500);
WIRE 16 -1 (-2225 3550)(-2225 3500);
WIRE 16 -1 (-1925 3550)(-2225 3550);
WIRE 16 -1 (-2225 3600)(-2225 3550);
WIRE 16 -1 (-1925 3600)(-2225 3600);
WIRE 16 -1 (-2225 3650)(-2225 3600);
WIRE 16 -1 (-1925 3650)(-2225 3650);
WIRE 16 -1 (-2225 3700)(-2225 3650);
WIRE 16 -1 (-1925 3700)(-2225 3700);
WIRE 16 -1 (-2225 3750)(-2225 3700);
WIRE 16 -1 (-1925 3750)(-2225 3750);
WIRE 16 -1 (-2225 3800)(-2225 3750);
WIRE 16 -1 (-1925 3800)(-2225 3800);
WIRE 16 -1 (-2225 3850)(-2225 3800);
WIRE 16 -1 (-1925 3850)(-2225 3850);
WIRE 16 -1 (-2225 3900)(-2225 3850);
WIRE 16 -1 (-1925 3900)(-2225 3900);
WIRE 16 -1 (-2225 3950)(-2225 3900);
WIRE 16 -1 (-1925 3950)(-2225 3950);
WIRE 16 -1 (-2225 4000)(-2225 3950);
WIRE 16 -1 (-1925 4000)(-2225 4000);
WIRE 16 -1 (-2225 4050)(-2225 4000);
WIRE 16 -1 (-2225 4100)(-2225 4050);
WIRE 16 -1 (-1925 4050)(-2225 4050);
WIRE 16 -1 (-1925 4100)(-2225 4100);
WIRE 16 -1 (-2225 4150)(-2225 4100);
WIRE 16 -1 (-1925 4150)(-2225 4150);
WIRE 16 -1 (-2225 4200)(-2225 4150);
WIRE 16 -1 (-1925 4200)(-2225 4200);
WIRE 16 -1 (-2225 4250)(-2225 4200);
WIRE 16 -1 (-1925 4250)(-2225 4250);
WIRE 16 -1 (-2225 4300)(-2225 4250);
WIRE 16 -1 (-1925 4300)(-2225 4300);
WIRE 16 -1 (-2225 4350)(-2225 4300);
WIRE 16 -1 (-1925 4350)(-2225 4350);
WIRE 16 -1 (-2225 4400)(-2225 4350);
WIRE 16 -1 (-1925 4400)(-2225 4400);
WIRE 16 -1 (-2225 4450)(-2225 4400);
WIRE 16 -1 (-1925 4450)(-2225 4450);
WIRE 16 -1 (-2225 4500)(-2225 4450);
WIRE 16 -1 (-1925 4500)(-2225 4500);
WIRE 16 -1 (-2225 4550)(-2225 4500);
WIRE 16 -1 (-1925 4550)(-2225 4550);
WIRE 16 -1 (-2225 4600)(-2225 4550);
WIRE 16 -1 (-1925 4600)(-2225 4600);
WIRE 16 -1 (-2225 4650)(-2225 4600);
WIRE 16 -1 (-1925 4650)(-2225 4650);
WIRE 16 -1 (-2225 4700)(-2225 4650);
WIRE 16 -1 (-1925 4700)(-2225 4700);
WIRE 16 -1 (-2225 4750)(-2225 4700);
WIRE 16 -1 (-1925 4750)(-2225 4750);
WIRE 16 -1 (-2225 4800)(-2225 4750);
WIRE 16 -1 (-1925 4800)(-2225 4800);
WIRE 16 -1 (-2225 4850)(-2225 4800);
WIRE 16 -1 (-1925 4850)(-2225 4850);
WIRE 16 -1 (-2225 4900)(-2225 4850);
WIRE 16 -1 (-1925 4900)(-2225 4900);
WIRE 16 -1 (-2225 4950)(-2225 4900);
WIRE 16 -1 (-1925 4950)(-2225 4950);
WIRE 16 -1 (-2225 5000)(-2225 4950);
WIRE 16 -1 (-1925 5000)(-2225 5000);
WIRE 16 -1 (-2225 5050)(-2225 5000);
WIRE 16 -1 (-1925 5050)(-2225 5050);
WIRE 16 -1 (-2225 5100)(-2225 5050);
WIRE 16 -1 (-1925 5100)(-2225 5100);
WIRE 16 -1 (-2225 5150)(-2225 5100);
WIRE 16 -1 (-1925 5150)(-2225 5150);
WIRE 16 -1 (-2225 5200)(-2225 5150);
WIRE 16 -1 (-1925 5200)(-2225 5200);
WIRE 16 -1 (-2225 5250)(-2225 5200);
WIRE 16 -1 (-1925 5250)(-2225 5250);
WIRE 16 -1 (-8375 2150)(-8375 2550);
WIRE 16 -1 (-8375 2150)(-8575 2150);
WIRE 16 -1 (-7650 2550)(-8375 2550);
FORCEPROP 2 LAST SIG_NAME PWRGD_CHC_CPU1_DIMM
J 0
(-8275 2560);
DISPLAY 0.489362 (-8275 2560);
FORCEPROP 2 LASTPROP $XRERR UNIQUE?
J 0
(-8515 2560);
DISPLAY 0.638298 (-8515 2560);
PAINT MONO (-8515 2560);
DISPLAY INVISIBLE (-8515 2560);
WIRE 16 -1 (-8575 2200)(-8575 2150);
WIRE 16 -1 (-8575 2150)(-8600 2150);
WIRE 16 -1 (-7650 3050)(-8275 3050);
FORCEPROP 2 LAST SIG_NAME M_C_CPU1_ALERT_N
J 0
(-8275 3060);
DISPLAY 0.489362 (-8275 3060);
WIRE 16 -1 (-8025 2625)(-8575 2625);
FORCEPROP 2 LAST SIG_NAME I3C_SPD_DDRAF_CPU1_SCL
J 0
(-8635 2635);
DISPLAY 0.489362 (-8635 2635);
WIRE 16 -1 (-8425 2850)(-8400 2850);
WIRE 16 -1 (-8425 2750)(-8425 2850);
WIRE 16 -1 (-8425 2750)(-8925 2750);
FORCEPROP 2 LAST SIG_NAME I3C_SPD_DDRAF_CPU1_SDA
J 0
(-8935 2760);
DISPLAY 0.489362 (-8935 2760);
WIRE 16 -1 (-8775 3325)(-8775 3350);
WIRE 16 -1 (-8775 3350)(-8675 3350);
WIRE 16 -1 (-8675 3375)(-8675 3350);
WIRE 16 -1 (-8675 3350)(-8675 2950);
WIRE 16 -1 (-8675 2950)(-7650 2950);
WIRE 16 -1 (-7650 2850)(-8200 2850);
FORCEPROP 2 LAST SIG_NAME I3C_SPD_DDRC_CPU1_SDA
J 0
(-8135 2860);
DISPLAY 0.446809 (-8135 2860);
FORCEPROP 2 LASTPROP $XRERR UNIQUE?
J 0
(-8375 2860);
DISPLAY 0.638298 (-8375 2860);
PAINT MONO (-8375 2860);
DISPLAY INVISIBLE (-8375 2860);
WIRE 16 -1 (-7750 2625)(-7825 2625);
WIRE 16 -1 (-7750 2800)(-7750 2625);
WIRE 16 -1 (-7650 2800)(-7750 2800);
FORCEPROP 2 LAST SIG_NAME I3C_SPD_DDRC_CPU1_SCL
J 0
(-8135 2810);
DISPLAY 0.446809 (-8135 2810);
FORCEPROP 2 LASTPROP $XRERR UNIQUE?
J 0
(-8375 2810);
DISPLAY 0.638298 (-8375 2810);
PAINT MONO (-8375 2810);
DISPLAY INVISIBLE (-8375 2810);
WIRE 16 -1 (-7650 2900)(-8675 2900);
FORCEPROP 2 LAST SIG_NAME PD_CHC_CPU1_DIMM_SAA
J 0
(-8675 2910);
DISPLAY 0.489362 (-8675 2910);
DOT 1 (-8675 3350);
DOT 1 (-425 5350);
DOT 1 (-425 5300);
DOT 1 (-425 5200);
DOT 1 (-425 5250);
DOT 1 (-425 5150);
DOT 1 (-425 5100);
DOT 1 (-425 5050);
DOT 1 (-425 5000);
DOT 1 (-425 4950);
DOT 1 (-425 4900);
DOT 1 (-425 4850);
DOT 1 (-425 4800);
DOT 1 (-425 4750);
DOT 1 (-425 4700);
DOT 1 (-425 4650);
DOT 1 (-425 4600);
DOT 1 (-425 4550);
DOT 1 (-425 4500);
DOT 1 (-425 4450);
DOT 1 (-425 4400);
DOT 1 (-425 4300);
DOT 1 (-425 4350);
DOT 1 (-425 4250);
DOT 1 (-425 4200);
DOT 1 (-425 4150);
DOT 1 (-425 4100);
DOT 1 (-425 4050);
DOT 1 (-425 4000);
DOT 1 (-425 3950);
DOT 1 (-425 3900);
DOT 1 (-425 3850);
DOT 1 (-425 3800);
DOT 1 (-2225 5350);
DOT 1 (-2225 5400);
DOT 1 (-2225 5200);
DOT 1 (-2225 5150);
DOT 1 (-2225 5100);
DOT 1 (-2225 5050);
DOT 1 (-2225 5000);
DOT 1 (-2225 4950);
DOT 1 (-2225 4900);
DOT 1 (-2225 4850);
DOT 1 (-2225 4800);
DOT 1 (-2225 4750);
DOT 1 (-2225 4700);
DOT 1 (-2225 4650);
DOT 1 (-2225 4550);
DOT 1 (-2225 4600);
DOT 1 (-2225 4500);
DOT 1 (-2225 4450);
DOT 1 (-2225 4400);
DOT 1 (-2225 4350);
DOT 1 (-2225 4300);
DOT 1 (-2225 4250);
DOT 1 (-2225 4200);
DOT 1 (-2225 4150);
DOT 1 (-2225 4100);
DOT 1 (-2225 4050);
DOT 1 (-2225 4000);
DOT 1 (-2225 3950);
DOT 1 (-2225 3900);
DOT 1 (-2225 3850);
DOT 1 (-2225 3800);
DOT 1 (-425 3750);
DOT 1 (-2225 3750);
DOT 1 (-425 3650);
DOT 1 (-425 3700);
DOT 1 (-425 3600);
DOT 1 (-425 3550);
DOT 1 (-425 3500);
DOT 1 (-425 3400);
DOT 1 (-425 3450);
DOT 1 (-425 3350);
DOT 1 (-425 3300);
DOT 1 (-425 3250);
DOT 1 (-425 3200);
DOT 1 (-425 3150);
DOT 1 (-425 3100);
DOT 1 (-425 3050);
DOT 1 (-425 3000);
DOT 1 (-425 2950);
DOT 1 (-425 2900);
DOT 1 (-425 2800);
DOT 1 (-425 2850);
DOT 1 (-425 2750);
DOT 1 (-425 2700);
DOT 1 (-425 2650);
DOT 1 (-425 2600);
DOT 1 (-425 2500);
DOT 1 (-425 2550);
DOT 1 (-425 2450);
DOT 1 (-425 2400);
DOT 1 (-425 2350);
DOT 1 (-425 2300);
DOT 1 (-425 2250);
DOT 1 (-425 2100);
DOT 1 (-425 2150);
DOT 1 (-425 2050);
DOT 1 (-2225 3650);
DOT 1 (-2225 3700);
DOT 1 (-2225 3600);
DOT 1 (-2225 3550);
DOT 1 (-2225 3500);
DOT 1 (-2225 3400);
DOT 1 (-2225 3450);
DOT 1 (-2225 3350);
DOT 1 (-2225 3300);
DOT 1 (-2225 3250);
DOT 1 (-2225 3200);
DOT 1 (-2225 3150);
DOT 1 (-2225 3100);
DOT 1 (-2225 3050);
DOT 1 (-2225 3000);
DOT 1 (-2225 2950);
DOT 1 (-2225 2900);
DOT 1 (-2225 2800);
DOT 1 (-2225 2850);
DOT 1 (-2225 2750);
DOT 1 (-2225 2700);
DOT 1 (-2225 2650);
DOT 1 (-2225 2600);
DOT 1 (-2225 2500);
DOT 1 (-2225 2550);
DOT 1 (-2225 2450);
DOT 1 (-2225 2400);
DOT 1 (-2225 2350);
DOT 1 (-2225 2300);
DOT 1 (-2225 2250);
DOT 1 (-2225 2150);
DOT 1 (-2225 2200);
DOT 1 (-8575 2150);
DOT 1 (-2925 5650);
DOT 1 (-2925 6075);
DOT 1 (-2350 6075);
QUIT
